(kicad_pcb
	(version 20241229)
	(generator "pcbnew")
	(generator_version "9.0")
	(general
		(thickness 0.876)
		(legacy_teardrops no)
	)
	(paper "A4")
	(title_block
		(rev "1.2.2")
	)
	(layers
		(0 "F.Cu" signal)
		(4 "In1.Cu" signal)
		(6 "In2.Cu" signal)
		(2 "B.Cu" signal)
		(9 "F.Adhes" user "F.Adhesive")
		(11 "B.Adhes" user "B.Adhesive")
		(13 "F.Paste" user)
		(15 "B.Paste" user)
		(5 "F.SilkS" user "F.Silkscreen")
		(7 "B.SilkS" user "B.Silkscreen")
		(1 "F.Mask" user)
		(3 "B.Mask" user)
		(17 "Dwgs.User" user "User.Drawings")
		(19 "Cmts.User" user "User.Comments")
		(21 "Eco1.User" user "User.Eco1")
		(23 "Eco2.User" user "User.Eco2")
		(25 "Edge.Cuts" user)
		(27 "Margin" user)
		(31 "F.CrtYd" user "F.Courtyard")
		(29 "B.CrtYd" user "B.Courtyard")
		(35 "F.Fab" user)
		(33 "B.Fab" user)
	)
	(setup
		(stackup
			(layer "F.SilkS"
				(type "Top Silk Screen")
			)
			(layer "F.Paste"
				(type "Top Solder Paste")
			)
			(layer "F.Mask"
				(type "Top Solder Mask")
				(thickness 0.01)
			)
			(layer "F.Cu"
				(type "copper")
				(thickness 0.018)
			)
			(layer "dielectric 1"
				(type "prepreg")
				(thickness 0.12)
				(material "FR4")
				(epsilon_r 4.2)
				(loss_tangent 0.02)
			)
			(layer "In1.Cu"
				(type "copper")
				(thickness 0.035)
			)
			(layer "dielectric 2"
				(type "core")
				(thickness 0.51)
				(material "FR4")
				(epsilon_r 4.5)
				(loss_tangent 0.02)
			)
			(layer "In2.Cu"
				(type "copper")
				(thickness 0.035)
			)
			(layer "dielectric 3"
				(type "prepreg")
				(thickness 0.12)
				(material "FR4")
				(epsilon_r 4.2)
				(loss_tangent 0.02)
			)
			(layer "B.Cu"
				(type "copper")
				(thickness 0.018)
			)
			(layer "B.Mask"
				(type "Bottom Solder Mask")
				(thickness 0.01)
			)
			(layer "B.Paste"
				(type "Bottom Solder Paste")
			)
			(layer "B.SilkS"
				(type "Bottom Silk Screen")
			)
			(copper_finish "None")
			(dielectric_constraints yes)
		)
		(pad_to_mask_clearance 0)
		(allow_soldermask_bridges_in_footprints no)
		(tenting front back)
		(grid_origin 111.600059 87.547277)
		(pcbplotparams
			(layerselection 0x00000000_00000000_55555555_5755f5ff)
			(plot_on_all_layers_selection 0x00000000_00000000_00000000_00000000)
			(disableapertmacros no)
			(usegerberextensions no)
			(usegerberattributes no)
			(usegerberadvancedattributes no)
			(creategerberjobfile no)
			(dashed_line_dash_ratio 12.000000)
			(dashed_line_gap_ratio 3.000000)
			(svgprecision 4)
			(plotframeref no)
			(mode 1)
			(useauxorigin no)
			(hpglpennumber 1)
			(hpglpenspeed 20)
			(hpglpendiameter 15.000000)
			(pdf_front_fp_property_popups yes)
			(pdf_back_fp_property_popups yes)
			(pdf_metadata yes)
			(pdf_single_document no)
			(dxfpolygonmode yes)
			(dxfimperialunits yes)
			(dxfusepcbnewfont yes)
			(psnegative no)
			(psa4output no)
			(plot_black_and_white yes)
			(sketchpadsonfab no)
			(plotpadnumbers no)
			(hidednponfab no)
			(sketchdnponfab yes)
			(crossoutdnponfab yes)
			(subtractmaskfromsilk no)
			(outputformat 1)
			(mirror no)
			(drillshape 0)
			(scaleselection 1)
			(outputdirectory "./pcb")
		)
	)
	(net 0 "")
	(net 1 "unconnected-(J1-PRSNT#2-PadB31)")
	(net 2 "unconnected-(J1-RSVD-PadB30)")
	(net 3 "unconnected-(J1-PRSNT#2-PadB17)")
	(net 4 "unconnected-(J1-RSVD-PadB12)")
	(net 5 "Net-(J1-WAKE#)")
	(net 6 "unconnected-(J1-JTAG1-PadB9)")
	(net 7 "unconnected-(J1-SMDAT-PadB6)")
	(net 8 "unconnected-(J1-SMCLK-PadB5)")
	(net 9 "unconnected-(J1-RSVD-PadA32)")
	(net 10 "unconnected-(J1-RSVD-PadA19)")
	(net 11 "Net-(J1-PWRGD)")
	(net 12 "unconnected-(J1-JTAG5-PadA8)")
	(net 13 "unconnected-(J1-JTAG4-PadA7)")
	(net 14 "unconnected-(J1-JTAG3-PadA6)")
	(net 15 "unconnected-(J1-JTAG2-PadA5)")
	(net 16 "unconnected-(J1-PRSNT#1-PadA1)")
	(net 17 "unconnected-(J2-PEDET-Pad69)")
	(net 18 "unconnected-(J2-SUSCLK-Pad68)")
	(net 19 "unconnected-(J2-NC-Pad67)")
	(net 20 "unconnected-(J2-NC-Pad58)")
	(net 21 "unconnected-(J2-NC-Pad56)")
	(net 22 "Net-(J2-CLKREQ#)")
	(net 23 "unconnected-(J2-NC-Pad48)")
	(net 24 "unconnected-(J2-NC-Pad46)")
	(net 25 "unconnected-(J2-NC-Pad44)")
	(net 26 "unconnected-(J2-NC-Pad42)")
	(net 27 "unconnected-(J2-NC-Pad40)")
	(net 28 "unconnected-(J2-DEVSLP-Pad38)")
	(net 29 "unconnected-(J2-NC-Pad36)")
	(net 30 "+12V")
	(net 31 "/+3V3")
	(net 32 "/REFCLK+")
	(net 33 "/REFCLK-")
	(net 34 "/Data_0_IN_N")
	(net 35 "/Data_0_IN_P")
	(net 36 "/Data_0_OUT_P")
	(net 37 "/Data_0_OUT_N")
	(net 38 "/Data_1_IN_N")
	(net 39 "/Data_1_IN_P")
	(net 40 "/Data_1_OUT_P")
	(net 41 "/Data_1_OUT_N")
	(net 42 "/Data_2_IN_N")
	(net 43 "/Data_2_IN_P")
	(net 44 "/Data_2_OUT_P")
	(net 45 "/Data_2_OUT_N")
	(net 46 "/Data_3_IN_N")
	(net 47 "/Data_3_IN_P")
	(net 48 "/Data_3_OUT_P")
	(net 49 "/Data_3_OUT_N")
	(net 50 "unconnected-(J2-NC-Pad34)")
	(net 51 "unconnected-(J2-NC-Pad32)")
	(net 52 "unconnected-(J2-NC-Pad30)")
	(net 53 "unconnected-(J2-NC-Pad28)")
	(net 54 "unconnected-(J2-NC-Pad26)")
	(net 55 "unconnected-(J2-NC-Pad24)")
	(net 56 "unconnected-(J2-NC-Pad22)")
	(net 57 "unconnected-(J2-NC-Pad20)")
	(net 58 "unconnected-(J2-DAS-Pad10)")
	(net 59 "/PWRGD")
	(net 60 "GND")
	(net 61 "+5V")
	(net 62 "/+3V3_AUX")
	(net 63 "/WAKE#")
	(net 64 "unconnected-(J2-NC-Pad8)")
	(net 65 "unconnected-(J2-NC-Pad6)")
	(footprint "antmicro-footprints:Socket_Samtec_PCIE_PCIe-x4_PCIE-064-02-X-D-EMSX"
		(layer "F.Cu")
		(at 131.660059 124.712277 180)
		(property "Reference" "J1"
			(at -16.84 9.265 180)
			(layer "F.SilkS")
			(effects
				(font
					(size 0.7 0.7)
					(thickness 0.15)
				)
				(justify left bottom)
			)
		)
		(property "Value" "Socket_Samtec_PCIE_PCIe-x4_PCIE-064-02-X-D-EMSX"
			(at 0 11.3 180)
			(layer "F.Fab")
			(effects
				(font
					(size 0.7 0.7)
					(thickness 0.15)
				)
				(justify left bottom)
			)
		)
		(property "Datasheet" "http://www.farnell.com/datasheets/2048385.pdf?_ga=2.224413790.550525831.1572511829-156563690.1566371002&_gac=1.194368863.1572511829.Cj0KCQjwjOrtBRCcARIsAEq4rW4MDAz553xUSGW1I2S05saoepO8CZq5otyVO6_gct6IiE-jnZiday4aAmKSEALw_wcB"
			(at 0 0 180)
			(layer "F.Fab")
			(hide yes)
			(effects
				(font
					(size 1.27 1.27)
					(thickness 0.15)
				)
			)
		)
		(property "Description" "PCIe x4 connector"
			(at 0 0 180)
			(layer "F.Fab")
			(hide yes)
			(effects
				(font
					(size 1.27 1.27)
					(thickness 0.15)
				)
			)
		)
		(property "Author" "Antmicro"
			(at 263.320118 249.424554 0)
			(layer "F.Fab")
			(hide yes)
			(effects
				(font
					(size 1 1)
					(thickness 0.15)
				)
			)
		)
		(property "License" "Apache-2.0"
			(at 263.320118 249.424554 0)
			(layer "F.Fab")
			(hide yes)
			(effects
				(font
					(size 1 1)
					(thickness 0.15)
				)
			)
		)
		(property "MPN" "PCIE-064-02-X-D-EMSX"
			(at 263.320118 249.424554 0)
			(layer "F.Fab")
			(hide yes)
			(effects
				(font
					(size 1 1)
					(thickness 0.15)
				)
			)
		)
		(property "Manufacturer" "Samtec"
			(at 263.320118 249.424554 0)
			(layer "F.Fab")
			(hide yes)
			(effects
				(font
					(size 1 1)
					(thickness 0.15)
				)
			)
		)
		(sheetname "/")
		(sheetfile "m2-pcie-adapter.kicad_sch")
		(attr smd)
		(fp_circle
			(center -17.1 7.6)
			(end -17.05 7.6)
			(stroke
				(width 0.15)
				(type solid)
			)
			(fill yes)
			(layer "F.SilkS")
		)
		(fp_rect
			(start -20.5 -9.03)
			(end 20.5 9.03)
			(stroke
				(width 0.05)
				(type solid)
			)
			(fill no)
			(layer "F.CrtYd")
		)
		(pad "A1" smd rect
			(at -16.55 5.9 180)
			(size 0.7 4.2)
			(layers "B.Cu" "B.Mask" "B.Paste")
			(net 16 "unconnected-(J1-PRSNT#1-PadA1)")
			(pinfunction "PRSNT#1")
			(pintype "passive+no_connect")
		)
		(pad "A2" smd rect
			(at -15.55 5.9 180)
			(size 0.7 4.2)
			(layers "B.Cu" "B.Mask" "B.Paste")
			(net 30 "+12V")
			(pinfunction "+12V")
			(pintype "passive")
		)
		(pad "A3" smd rect
			(at -14.55 5.9 180)
			(size 0.7 4.2)
			(layers "B.Cu" "B.Mask" "B.Paste")
			(net 30 "+12V")
			(pinfunction "+12V")
			(pintype "passive")
		)
		(pad "A4" smd rect
			(at -13.55 5.9 180)
			(size 0.7 4.2)
			(layers "B.Cu" "B.Mask" "B.Paste")
			(net 60 "GND")
			(pinfunction "GND")
			(pintype "passive")
		)
		(pad "A5" smd rect
			(at -12.55 5.9 180)
			(size 0.7 4.2)
			(layers "B.Cu" "B.Mask" "B.Paste")
			(net 15 "unconnected-(J1-JTAG2-PadA5)")
			(pinfunction "JTAG2")
			(pintype "passive+no_connect")
		)
		(pad "A6" smd rect
			(at -11.55 5.9 180)
			(size 0.7 4.2)
			(layers "B.Cu" "B.Mask" "B.Paste")
			(net 14 "unconnected-(J1-JTAG3-PadA6)")
			(pinfunction "JTAG3")
			(pintype "passive+no_connect")
		)
		(pad "A7" smd rect
			(at -10.55 5.9 180)
			(size 0.7 4.2)
			(layers "B.Cu" "B.Mask" "B.Paste")
			(net 13 "unconnected-(J1-JTAG4-PadA7)")
			(pinfunction "JTAG4")
			(pintype "passive+no_connect")
		)
		(pad "A8" smd rect
			(at -9.55 5.9 180)
			(size 0.7 4.2)
			(layers "B.Cu" "B.Mask" "B.Paste")
			(net 12 "unconnected-(J1-JTAG5-PadA8)")
			(pinfunction "JTAG5")
			(pintype "passive+no_connect")
		)
		(pad "A9" smd rect
			(at -8.55 5.9 180)
			(size 0.7 4.2)
			(layers "B.Cu" "B.Mask" "B.Paste")
			(net 31 "/+3V3")
			(pinfunction "+3V3")
			(pintype "passive")
		)
		(pad "A10" smd rect
			(at -7.55 5.9 180)
			(size 0.7 4.2)
			(layers "B.Cu" "B.Mask" "B.Paste")
			(net 31 "/+3V3")
			(pinfunction "+3V3")
			(pintype "passive")
		)
		(pad "A11" smd rect
			(at -6.55 5.9 180)
			(size 0.7 4.2)
			(layers "B.Cu" "B.Mask" "B.Paste")
			(net 11 "Net-(J1-PWRGD)")
			(pinfunction "PWRGD")
			(pintype "passive")
		)
		(pad "A12" smd rect
			(at -3.55 5.9 180)
			(size 0.7 4.2)
			(layers "B.Cu" "B.Mask" "B.Paste")
			(net 60 "GND")
			(pinfunction "GND")
			(pintype "passive")
		)
		(pad "A13" smd rect
			(at -2.55 5.9 180)
			(size 0.7 4.2)
			(layers "B.Cu" "B.Mask" "B.Paste")
			(net 32 "/REFCLK+")
			(pinfunction "REFCLK+")
			(pintype "passive")
		)
		(pad "A14" smd rect
			(at -1.55 5.9 180)
			(size 0.7 4.2)
			(layers "B.Cu" "B.Mask" "B.Paste")
			(net 33 "/REFCLK-")
			(pinfunction "REFCLK-")
			(pintype "passive")
		)
		(pad "A15" smd rect
			(at -0.55 5.9 180)
			(size 0.7 4.2)
			(layers "B.Cu" "B.Mask" "B.Paste")
			(net 60 "GND")
			(pinfunction "GND")
			(pintype "passive")
		)
		(pad "A16" smd rect
			(at 0.45 5.9 180)
			(size 0.7 4.2)
			(layers "B.Cu" "B.Mask" "B.Paste")
			(net 35 "/Data_0_IN_P")
			(pinfunction "HSIp(0)")
			(pintype "passive")
		)
		(pad "A17" smd rect
			(at 1.45 5.9 180)
			(size 0.7 4.2)
			(layers "B.Cu" "B.Mask" "B.Paste")
			(net 34 "/Data_0_IN_N")
			(pinfunction "HSIn(0)")
			(pintype "passive")
		)
		(pad "A18" smd rect
			(at 2.45 5.9 180)
			(size 0.7 4.2)
			(layers "B.Cu" "B.Mask" "B.Paste")
			(net 60 "GND")
			(pinfunction "GND")
			(pintype "passive")
		)
		(pad "A19" smd rect
			(at 3.45 5.9 180)
			(size 0.7 4.2)
			(layers "B.Cu" "B.Mask" "B.Paste")
			(net 10 "unconnected-(J1-RSVD-PadA19)")
			(pinfunction "RSVD")
			(pintype "passive+no_connect")
		)
		(pad "A20" smd rect
			(at 4.45 5.9 180)
			(size 0.7 4.2)
			(layers "B.Cu" "B.Mask" "B.Paste")
			(net 60 "GND")
			(pinfunction "GND")
			(pintype "passive")
		)
		(pad "A21" smd rect
			(at 5.45 5.9 180)
			(size 0.7 4.2)
			(layers "B.Cu" "B.Mask" "B.Paste")
			(net 39 "/Data_1_IN_P")
			(pinfunction "HSIp(1)")
			(pintype "passive")
		)
		(pad "A22" smd rect
			(at 6.45 5.9 180)
			(size 0.7 4.2)
			(layers "B.Cu" "B.Mask" "B.Paste")
			(net 38 "/Data_1_IN_N")
			(pinfunction "HSIn(1)")
			(pintype "passive")
		)
		(pad "A23" smd rect
			(at 7.45 5.9 180)
			(size 0.7 4.2)
			(layers "B.Cu" "B.Mask" "B.Paste")
			(net 60 "GND")
			(pinfunction "GND")
			(pintype "passive")
		)
		(pad "A24" smd rect
			(at 8.45 5.9 180)
			(size 0.7 4.2)
			(layers "B.Cu" "B.Mask" "B.Paste")
			(net 60 "GND")
			(pinfunction "GND")
			(pintype "passive")
		)
		(pad "A25" smd rect
			(at 9.45 5.9 180)
			(size 0.7 4.2)
			(layers "B.Cu" "B.Mask" "B.Paste")
			(net 43 "/Data_2_IN_P")
			(pinfunction "HSIp(2)")
			(pintype "passive")
		)
		(pad "A26" smd rect
			(at 10.45 5.9 180)
			(size 0.7 4.2)
			(layers "B.Cu" "B.Mask" "B.Paste")
			(net 42 "/Data_2_IN_N")
			(pinfunction "HSIn(2)")
			(pintype "passive")
		)
		(pad "A27" smd rect
			(at 11.45 5.9 180)
			(size 0.7 4.2)
			(layers "B.Cu" "B.Mask" "B.Paste")
			(net 60 "GND")
			(pinfunction "GND")
			(pintype "passive")
		)
		(pad "A28" smd rect
			(at 12.45 5.9 180)
			(size 0.7 4.2)
			(layers "B.Cu" "B.Mask" "B.Paste")
			(net 60 "GND")
			(pinfunction "GND")
			(pintype "input")
		)
		(pad "A29" smd rect
			(at 13.45 5.9 180)
			(size 0.7 4.2)
			(layers "B.Cu" "B.Mask" "B.Paste")
			(net 47 "/Data_3_IN_P")
			(pinfunction "HSIp(3)")
			(pintype "passive")
		)
		(pad "A30" smd rect
			(at 14.45 5.9 180)
			(size 0.7 4.2)
			(layers "B.Cu" "B.Mask" "B.Paste")
			(net 46 "/Data_3_IN_N")
			(pinfunction "HSIn(3)")
			(pintype "passive")
		)
		(pad "A31" smd rect
			(at 15.45 5.9 180)
			(size 0.7 4.2)
			(layers "B.Cu" "B.Mask" "B.Paste")
			(net 60 "GND")
			(pinfunction "GND")
			(pintype "passive")
		)
		(pad "A32" smd rect
			(at 16.45 5.9 180)
			(size 0.7 4.2)
			(layers "B.Cu" "B.Mask" "B.Paste")
			(net 9 "unconnected-(J1-RSVD-PadA32)")
			(pinfunction "RSVD")
			(pintype "passive+no_connect")
		)
		(pad "B1" smd rect
			(at -16.55 5.895 180)
			(size 0.7 4.2)
			(layers "F.Cu" "F.Mask" "F.Paste")
			(net 30 "+12V")
			(pinfunction "+12V")
			(pintype "passive")
		)
		(pad "B2" smd rect
			(at -15.55 5.895 180)
			(size 0.7 4.2)
			(layers "F.Cu" "F.Mask" "F.Paste")
			(net 30 "+12V")
			(pinfunction "+12V")
			(pintype "passive")
		)
		(pad "B3" smd rect
			(at -14.55 5.895 180)
			(size 0.7 4.2)
			(layers "F.Cu" "F.Mask" "F.Paste")
			(net 30 "+12V")
			(pinfunction "+12V")
			(pintype "passive")
		)
		(pad "B4" smd rect
			(at -13.55 5.895 180)
			(size 0.7 4.2)
			(layers "F.Cu" "F.Mask" "F.Paste")
			(net 60 "GND")
			(pinfunction "GND")
			(pintype "passive")
		)
		(pad "B5" smd rect
			(at -12.55 5.895 180)
			(size 0.7 4.2)
			(layers "F.Cu" "F.Mask" "F.Paste")
			(net 8 "unconnected-(J1-SMCLK-PadB5)")
			(pinfunction "SMCLK")
			(pintype "passive+no_connect")
		)
		(pad "B6" smd rect
			(at -11.55 5.895 180)
			(size 0.7 4.2)
			(layers "F.Cu" "F.Mask" "F.Paste")
			(net 7 "unconnected-(J1-SMDAT-PadB6)")
			(pinfunction "SMDAT")
			(pintype "passive+no_connect")
		)
		(pad "B7" smd rect
			(at -10.55 5.895 180)
			(size 0.7 4.2)
			(layers "F.Cu" "F.Mask" "F.Paste")
			(net 60 "GND")
			(pinfunction "GND")
			(pintype "passive")
		)
		(pad "B8" smd rect
			(at -9.55 5.895 180)
			(size 0.7 4.2)
			(layers "F.Cu" "F.Mask" "F.Paste")
			(net 31 "/+3V3")
			(pinfunction "+3V3")
			(pintype "passive")
		)
		(pad "B9" smd rect
			(at -8.55 5.895 180)
			(size 0.7 4.2)
			(layers "F.Cu" "F.Mask" "F.Paste")
			(net 6 "unconnected-(J1-JTAG1-PadB9)")
			(pinfunction "JTAG1")
			(pintype "passive+no_connect")
		)
		(pad "B10" smd rect
			(at -7.55 5.895 180)
			(size 0.7 4.2)
			(layers "F.Cu" "F.Mask" "F.Paste")
			(net 62 "/+3V3_AUX")
			(pinfunction "+3V3aux")
			(pintype "passive")
		)
		(pad "B11" smd rect
			(at -6.55 5.895 180)
			(size 0.7 4.2)
			(layers "F.Cu" "F.Mask" "F.Paste")
			(net 5 "Net-(J1-WAKE#)")
			(pinfunction "WAKE#")
			(pintype "passive")
		)
		(pad "B12" smd rect
			(at -3.55 5.895 180)
			(size 0.7 4.2)
			(layers "F.Cu" "F.Mask" "F.Paste")
			(net 4 "unconnected-(J1-RSVD-PadB12)")
			(pinfunction "RSVD")
			(pintype "passive+no_connect")
		)
		(pad "B13" smd rect
			(at -2.55 5.895 180)
			(size 0.7 4.2)
			(layers "F.Cu" "F.Mask" "F.Paste")
			(net 60 "GND")
			(pinfunction "GND")
			(pintype "passive")
		)
		(pad "B14" smd rect
			(at -1.55 5.895 180)
			(size 0.7 4.2)
			(layers "F.Cu" "F.Mask" "F.Paste")
			(net 36 "/Data_0_OUT_P")
			(pinfunction "HSOp(0)")
			(pintype "passive")
		)
		(pad "B15" smd rect
			(at -0.55 5.895 180)
			(size 0.7 4.2)
			(layers "F.Cu" "F.Mask" "F.Paste")
			(net 37 "/Data_0_OUT_N")
			(pinfunction "HSOn(0)")
			(pintype "passive")
		)
		(pad "B16" smd rect
			(at 0.45 5.895 180)
			(size 0.7 4.2)
			(layers "F.Cu" "F.Mask" "F.Paste")
			(net 60 "GND")
			(pinfunction "GND")
			(pintype "passive")
		)
		(pad "B17" smd rect
			(at 1.45 5.895 180)
			(size 0.7 4.2)
			(layers "F.Cu" "F.Mask" "F.Paste")
			(net 3 "unconnected-(J1-PRSNT#2-PadB17)")
			(pinfunction "PRSNT#2")
			(pintype "passive+no_connect")
		)
		(pad "B18" smd rect
			(at 2.45 5.895 180)
			(size 0.7 4.2)
			(layers "F.Cu" "F.Mask" "F.Paste")
			(net 60 "GND")
			(pinfunction "GND")
			(pintype "passive")
		)
		(pad "B19" smd rect
			(at 3.45 5.895 180)
			(size 0.7 4.2)
			(layers "F.Cu" "F.Mask" "F.Paste")
			(net 40 "/Data_1_OUT_P")
			(pinfunction "HSOp(1)")
			(pintype "passive")
		)
		(pad "B20" smd rect
			(at 4.45 5.895 180)
			(size 0.7 4.2)
			(layers "F.Cu" "F.Mask" "F.Paste")
			(net 41 "/Data_1_OUT_N")
			(pinfunction "HSOn(1)")
			(pintype "passive")
		)
		(pad "B21" smd rect
			(at 5.45 5.895 180)
			(size 0.7 4.2)
			(layers "F.Cu" "F.Mask" "F.Paste")
			(net 60 "GND")
			(pinfunction "GND")
			(pintype "passive")
		)
		(pad "B22" smd rect
			(at 6.45 5.895 180)
			(size 0.7 4.2)
			(layers "F.Cu" "F.Mask" "F.Paste")
			(net 60 "GND")
			(pinfunction "GND")
			(pintype "passive")
		)
		(pad "B23" smd rect
			(at 7.45 5.895 180)
			(size 0.7 4.2)
			(layers "F.Cu" "F.Mask" "F.Paste")
			(net 44 "/Data_2_OUT_P")
			(pinfunction "HSOp(2)")
			(pintype "passive")
		)
		(pad "B24" smd rect
			(at 8.45 5.895 180)
			(size 0.7 4.2)
			(layers "F.Cu" "F.Mask" "F.Paste")
			(net 45 "/Data_2_OUT_N")
			(pinfunction "HSOn(2)")
			(pintype "passive")
		)
		(pad "B25" smd rect
			(at 9.45 5.895 180)
			(size 0.7 4.2)
			(layers "F.Cu" "F.Mask" "F.Paste")
			(net 60 "GND")
			(pinfunction "GND")
			(pintype "passive")
		)
		(pad "B26" smd rect
			(at 10.45 5.895 180)
			(size 0.7 4.2)
			(layers "F.Cu" "F.Mask" "F.Paste")
			(net 60 "GND")
			(pinfunction "GND")
			(pintype "passive")
		)
		(pad "B27" smd rect
			(at 11.45 5.895 180)
			(size 0.7 4.2)
			(layers "F.Cu" "F.Mask" "F.Paste")
			(net 48 "/Data_3_OUT_P")
			(pinfunction "HSOp(3)")
			(pintype "passive")
		)
		(pad "B28" smd rect
			(at 12.45 5.895 180)
			(size 0.7 4.2)
			(layers "F.Cu" "F.Mask" "F.Paste")
			(net 49 "/Data_3_OUT_N")
			(pinfunction "HSOn(3)")
			(pintype "passive")
		)
		(pad "B29" smd rect
			(at 13.45 5.895 180)
			(size 0.7 4.2)
			(layers "F.Cu" "F.Mask" "F.Paste")
			(net 60 "GND")
			(pinfunction "GND")
			(pintype "passive")
		)
		(pad "B30" smd rect
			(at 14.45 5.895 180)
			(size 0.7 4.2)
			(layers "F.Cu" "F.Mask" "F.Paste")
			(net 2 "unconnected-(J1-RSVD-PadB30)")
			(pinfunction "RSVD")
			(pintype "passive+no_connect")
		)
		(pad "B31" smd rect
			(at 15.45 5.895 180)
			(size 0.7 4.2)
			(layers "F.Cu" "F.Mask" "F.Paste")
			(net 1 "unconnected-(J1-PRSNT#2-PadB31)")
			(pinfunction "PRSNT#2")
			(pintype "passive+no_connect")
		)
		(pad "B32" smd rect
			(at 16.45 5.895 180)
			(size 0.7 4.2)
			(layers "F.Cu" "F.Mask" "F.Paste")
			(net 60 "GND")
			(pinfunction "GND")
			(pintype "passive")
		)
	)
	(footprint "antmicro-footprints:Harwin_1x1_H3.5mm_Pad2.2mm_P70-1000045R"
		(layer "F.Cu")
		(at 179.200059 101.287277)
		(property "Reference" "J4"
			(at 0 -1.31 0)
			(layer "F.SilkS")
			(effects
				(font
					(size 0.7 0.7)
					(thickness 0.15)
				)
				(justify left bottom)
			)
		)
		(property "Value" "Harwin_1x1_H3.5mm_Pad2.2mm_P70-1000045R"
			(at 0 2.2 0)
			(layer "F.Fab")
			(effects
				(font
					(size 0.7 0.7)
					(thickness 0.15)
				)
				(justify left bottom)
			)
		)
		(property "Datasheet" "https://eu.mouser.com/datasheet/2/181/P70_10X-1018735.pdf"
			(at 0 0 0)
			(layer "F.Fab")
			(hide yes)
			(effects
				(font
					(size 1.27 1.27)
					(thickness 0.15)
				)
			)
		)
		(property "Description" "Contact Spring Surface Mount"
			(at 0 0 0)
			(layer "F.Fab")
			(hide yes)
			(effects
				(font
					(size 1.27 1.27)
					(thickness 0.15)
				)
			)
		)
		(property "Author" "Antmicro"
			(at 0 0 0)
			(layer "F.Fab")
			(hide yes)
			(effects
				(font
					(size 1 1)
					(thickness 0.15)
				)
			)
		)
		(property "License" "Apache-2.0"
			(at 0 0 0)
			(layer "F.Fab")
			(hide yes)
			(effects
				(font
					(size 1 1)
					(thickness 0.15)
				)
			)
		)
		(property "MPN" "P70-1000045R"
			(at 0 0 0)
			(layer "F.Fab")
			(hide yes)
			(effects
				(font
					(size 1 1)
					(thickness 0.15)
				)
			)
		)
		(property "Manufacturer" "Harwin"
			(at 0 0 0)
			(layer "F.Fab")
			(hide yes)
			(effects
				(font
					(size 1 1)
					(thickness 0.15)
				)
			)
		)
		(sheetname "/")
		(sheetfile "m2-pcie-adapter.kicad_sch")
		(attr smd)
		(fp_circle
			(center 0 0)
			(end 1.18 0)
			(stroke
				(width 0.15)
				(type solid)
			)
			(fill no)
			(layer "F.SilkS")
		)
		(fp_circle
			(center 0 0)
			(end 0 -1.25)
			(stroke
				(width 0.05)
				(type solid)
			)
			(fill no)
			(layer "F.CrtYd")
		)
		(pad "1" smd circle
			(at 0 0)
			(size 2.2 2.2)
			(layers "F.Cu" "F.Mask" "F.Paste")
			(net 30 "+12V")
			(pintype "passive")
		)
	)
	(footprint "antmicro-footprints:Harwin_1x1_H3.5mm_Pad2.2mm_P70-1000045R"
		(layer "F.Cu")
		(at 179.190059 96.267277)
		(property "Reference" "J5"
			(at 0 -1.31 0)
			(layer "F.SilkS")
			(effects
				(font
					(size 0.7 0.7)
					(thickness 0.15)
				)
				(justify left bottom)
			)
		)
		(property "Value" "Harwin_1x1_H3.5mm_Pad2.2mm_P70-1000045R"
			(at 0 2.2 0)
			(layer "F.Fab")
			(effects
				(font
					(size 0.7 0.7)
					(thickness 0.15)
				)
				(justify left bottom)
			)
		)
		(property "Datasheet" "https://eu.mouser.com/datasheet/2/181/P70_10X-1018735.pdf"
			(at 0 0 0)
			(layer "F.Fab")
			(hide yes)
			(effects
				(font
					(size 1.27 1.27)
					(thickness 0.15)
				)
			)
		)
		(property "Description" "Contact Spring Surface Mount"
			(at 0 0 0)
			(layer "F.Fab")
			(hide yes)
			(effects
				(font
					(size 1.27 1.27)
					(thickness 0.15)
				)
			)
		)
		(property "Author" "Antmicro"
			(at 0 0 0)
			(layer "F.Fab")
			(hide yes)
			(effects
				(font
					(size 1 1)
					(thickness 0.15)
				)
			)
		)
		(property "License" "Apache-2.0"
			(at 0 0 0)
			(layer "F.Fab")
			(hide yes)
			(effects
				(font
					(size 1 1)
					(thickness 0.15)
				)
			)
		)
		(property "MPN" "P70-1000045R"
			(at 0 0 0)
			(layer "F.Fab")
			(hide yes)
			(effects
				(font
					(size 1 1)
					(thickness 0.15)
				)
			)
		)
		(property "Manufacturer" "Harwin"
			(at 0 0 0)
			(layer "F.Fab")
			(hide yes)
			(effects
				(font
					(size 1 1)
					(thickness 0.15)
				)
			)
		)
		(sheetname "/")
		(sheetfile "m2-pcie-adapter.kicad_sch")
		(attr smd)
		(fp_circle
			(center 0 0)
			(end 1.18 0)
			(stroke
				(width 0.15)
				(type solid)
			)
			(fill no)
			(layer "F.SilkS")
		)
		(fp_circle
			(center 0 0)
			(end 0 -1.25)
			(stroke
				(width 0.05)
				(type solid)
			)
			(fill no)
			(layer "F.CrtYd")
		)
		(pad "1" smd circle
			(at 0 0)
			(size 2.2 2.2)
			(layers "F.Cu" "F.Mask" "F.Paste")
			(net 61 "+5V")
			(pintype "passive")
		)
	)
	(footprint "antmicro-footprints:PCB-Edge_M.2_Key-M"
		(layer "B.Cu")
		(at 106.200059 98.36752 90)
		(property "Reference" "J2"
			(at -0.05 6.025 90)
			(layer "B.SilkS")
			(hide yes)
			(effects
				(font
					(size 0.7 0.7)
					(thickness 0.15)
				)
				(justify right bottom mirror)
			)
		)
		(property "Value" "PCB-Edge_M.2_Key-M"
			(at -0.075 -2.25 90)
			(layer "B.Fab")
			(effects
				(font
					(size 0.7 0.7)
					(thickness 0.15)
				)
				(justify right bottom mirror)
			)
		)
		(property "Datasheet" "https://www.amphenol-icc.com/media/wysiwyg/files/drawing/10130618.pdf"
			(at 0 0 90)
			(layer "F.Fab")
			(hide yes)
			(effects
				(font
					(size 1.27 1.27)
					(thickness 0.15)
				)
			)
		)
		(property "Description" "PCB Edge for M.2 key M"
			(at 0 0 90)
			(layer "F.Fab")
			(hide yes)
			(effects
				(font
					(size 1.27 1.27)
					(thickness 0.15)
				)
			)
		)
		(property "Author" "Antmicro"
			(at 204.567579 -7.832539 0)
			(layer "B.Fab")
			(hide yes)
			(effects
				(font
					(size 1 1)
					(thickness 0.15)
				)
				(justify mirror)
			)
		)
		(property "License" "Apache-2.0"
			(at 204.567579 -7.832539 0)
			(layer "B.Fab")
			(hide yes)
			(effects
				(font
					(size 1 1)
					(thickness 0.15)
				)
				(justify mirror)
			)
		)
		(property "Public" "False"
			(at 204.567579 -7.832539 0)
			(layer "B.Fab")
			(hide yes)
			(effects
				(font
					(size 1 1)
					(thickness 0.15)
				)
				(justify mirror)
			)
		)
		(sheetname "/")
		(sheetfile "m2-pcie-adapter.kicad_sch")
		(attr exclude_from_pos_files exclude_from_bom)
		(fp_rect
			(start -10.075 0)
			(end 9.775 4)
			(stroke
				(width 0.05)
				(type solid)
			)
			(fill no)
			(layer "B.CrtYd")
		)
		(fp_rect
			(start -11.15 5.2)
			(end 10.85 0)
			(stroke
				(width 0.05)
				(type solid)
			)
			(fill no)
			(layer "F.CrtYd")
		)
		(pad "1" smd rect
			(at 9.1 1.45 90)
			(size 0.35 2.5)
			(layers "B.Cu" "B.Mask")
			(net 60 "GND")
			(pinfunction "GND")
			(pintype "passive")
		)
		(pad "2" smd rect
			(at 8.845243 1.7 90)
			(size 0.35 3)
			(layers "F.Cu" "F.Mask")
			(net 31 "/+3V3")
			(pinfunction "3.3V")
			(pintype "passive")
		)
		(pad "3" smd rect
			(at 8.6 1.45 90)
			(size 0.35 2.5)
			(layers "B.Cu" "B.Mask")
			(net 60 "GND")
			(pinfunction "GND")
			(pintype "passive")
		)
		(pad "4" smd rect
			(at 8.345243 1.7 90)
			(size 0.35 3)
			(layers "F.Cu" "F.Mask")
			(net 31 "/+3V3")
			(pinfunction "3.3V")
			(pintype "passive")
		)
		(pad "5" smd rect
			(at 8.1 1.45 90)
			(size 0.35 2.5)
			(layers "B.Cu" "B.Mask")
			(net 46 "/Data_3_IN_N")
			(pinfunction "PERn3")
			(pintype "passive")
		)
		(pad "6" smd rect
			(at 7.845243 1.7 90)
			(size 0.35 3)
			(layers "F.Cu" "F.Mask")
			(net 65 "unconnected-(J2-NC-Pad6)")
			(pinfunction "NC")
			(pintype "no_connect")
		)
		(pad "7" smd rect
			(at 7.6 1.45 90)
			(size 0.35 2.5)
			(layers "B.Cu" "B.Mask")
			(net 47 "/Data_3_IN_P")
			(pinfunction "PERp3")
			(pintype "passive")
		)
		(pad "8" smd rect
			(at 7.345243 1.7 90)
			(size 0.35 3)
			(layers "F.Cu" "F.Mask")
			(net 64 "unconnected-(J2-NC-Pad8)")
			(pinfunction "NC")
			(pintype "no_connect")
		)
		(pad "9" smd rect
			(at 7.1 1.45 90)
			(size 0.35 2.5)
			(layers "B.Cu" "B.Mask")
			(net 60 "GND")
			(pinfunction "GND")
			(pintype "passive")
		)
		(pad "10" smd rect
			(at 6.845243 1.7 90)
			(size 0.35 3)
			(layers "F.Cu" "F.Mask")
			(net 58 "unconnected-(J2-DAS-Pad10)")
			(pinfunction "DAS")
			(pintype "passive+no_connect")
		)
		(pad "11" smd rect
			(at 6.6 1.45 90)
			(size 0.35 2.5)
			(layers "B.Cu" "B.Mask")
			(net 49 "/Data_3_OUT_N")
			(pinfunction "PETn3")
			(pintype "passive")
		)
		(pad "12" smd rect
			(at 6.345243 1.7 90)
			(size 0.35 3)
			(layers "F.Cu" "F.Mask")
			(net 31 "/+3V3")
			(pinfunction "3.3V")
			(pintype "power_in")
		)
		(pad "13" smd rect
			(at 6.1 1.45 90)
			(size 0.35 2.5)
			(layers "B.Cu" "B.Mask")
			(net 48 "/Data_3_OUT_P")
			(pinfunction "PETp3")
			(pintype "passive")
		)
		(pad "14" smd rect
			(at 5.845243 1.7 90)
			(size 0.35 3)
			(layers "F.Cu" "F.Mask")
			(net 31 "/+3V3")
			(pinfunction "3.3V")
			(pintype "passive")
		)
		(pad "15" smd rect
			(at 5.6 1.45 90)
			(size 0.35 2.5)
			(layers "B.Cu" "B.Mask")
			(net 60 "GND")
			(pinfunction "GND")
			(pintype "passive")
		)
		(pad "16" smd rect
			(at 5.345243 1.7 90)
			(size 0.35 3)
			(layers "F.Cu" "F.Mask")
			(net 31 "/+3V3")
			(pinfunction "3.3V")
			(pintype "passive")
		)
		(pad "17" smd rect
			(at 5.1 1.45 90)
			(size 0.35 2.5)
			(layers "B.Cu" "B.Mask")
			(net 42 "/Data_2_IN_N")
			(pinfunction "PERn2")
			(pintype "passive")
		)
		(pad "18" smd rect
			(at 4.845243 1.7 90)
			(size 0.35 3)
			(layers "F.Cu" "F.Mask")
			(net 31 "/+3V3")
			(pinfunction "3.3V")
			(pintype "passive")
		)
		(pad "19" smd rect
			(at 4.6 1.45 90)
			(size 0.35 2.5)
			(layers "B.Cu" "B.Mask")
			(net 43 "/Data_2_IN_P")
			(pinfunction "PERp2")
			(pintype "passive")
		)
		(pad "20" smd rect
			(at 4.345243 1.7 90)
			(size 0.35 3)
			(layers "F.Cu" "F.Mask")
			(net 57 "unconnected-(J2-NC-Pad20)")
			(pinfunction "NC")
			(pintype "no_connect")
		)
		(pad "21" smd rect
			(at 4.1 1.45 90)
			(size 0.35 2.5)
			(layers "B.Cu" "B.Mask")
			(net 60 "GND")
			(pinfunction "GND")
			(pintype "passive")
		)
		(pad "22" smd rect
			(at 3.845243 1.7 90)
			(size 0.35 3)
			(layers "F.Cu" "F.Mask")
			(net 56 "unconnected-(J2-NC-Pad22)")
			(pinfunction "NC")
			(pintype "no_connect")
		)
		(pad "23" smd rect
			(at 3.6 1.45 90)
			(size 0.35 2.5)
			(layers "B.Cu" "B.Mask")
			(net 45 "/Data_2_OUT_N")
			(pinfunction "PETn2")
			(pintype "passive")
		)
		(pad "24" smd rect
			(at 3.345243 1.7 90)
			(size 0.35 3)
			(layers "F.Cu" "F.Mask")
			(net 55 "unconnected-(J2-NC-Pad24)")
			(pinfunction "NC")
			(pintype "no_connect")
		)
		(pad "25" smd rect
			(at 3.1 1.45 90)
			(size 0.35 2.5)
			(layers "B.Cu" "B.Mask")
			(net 44 "/Data_2_OUT_P")
			(pinfunction "PETp2")
			(pintype "passive")
		)
		(pad "26" smd rect
			(at 2.845243 1.7 90)
			(size 0.35 3)
			(layers "F.Cu" "F.Mask")
			(net 54 "unconnected-(J2-NC-Pad26)")
			(pinfunction "NC")
			(pintype "no_connect")
		)
		(pad "27" smd rect
			(at 2.6 1.45 90)
			(size 0.35 2.5)
			(layers "B.Cu" "B.Mask")
			(net 60 "GND")
			(pinfunction "GND")
			(pintype "passive")
		)
		(pad "28" smd rect
			(at 2.345243 1.7 90)
			(size 0.35 3)
			(layers "F.Cu" "F.Mask")
			(net 53 "unconnected-(J2-NC-Pad28)")
			(pinfunction "NC")
			(pintype "no_connect")
		)
		(pad "29" smd rect
			(at 2.1 1.45 90)
			(size 0.35 2.5)
			(layers "B.Cu" "B.Mask")
			(net 38 "/Data_1_IN_N")
			(pinfunction "PERn1")
			(pintype "passive")
		)
		(pad "30" smd rect
			(at 1.845243 1.7 90)
			(size 0.35 3)
			(layers "F.Cu" "F.Mask")
			(net 52 "unconnected-(J2-NC-Pad30)")
			(pinfunction "NC")
			(pintype "no_connect")
		)
		(pad "31" smd rect
			(at 1.6 1.45 90)
			(size 0.35 2.5)
			(layers "B.Cu" "B.Mask")
			(net 39 "/Data_1_IN_P")
			(pinfunction "PERp1")
			(pintype "passive")
		)
		(pad "32" smd rect
			(at 1.345243 1.7 90)
			(size 0.35 3)
			(layers "F.Cu" "F.Mask")
			(net 51 "unconnected-(J2-NC-Pad32)")
			(pinfunction "NC")
			(pintype "no_connect")
		)
		(pad "33" smd rect
			(at 1.1 1.45 90)
			(size 0.35 2.5)
			(layers "B.Cu" "B.Mask")
			(net 60 "GND")
			(pinfunction "GND")
			(pintype "passive")
		)
		(pad "34" smd rect
			(at 0.845243 1.7 90)
			(size 0.35 3)
			(layers "F.Cu" "F.Mask")
			(net 50 "unconnected-(J2-NC-Pad34)")
			(pinfunction "NC")
			(pintype "no_connect")
		)
		(pad "35" smd rect
			(at 0.6 1.45 90)
			(size 0.35 2.5)
			(layers "B.Cu" "B.Mask")
			(net 41 "/Data_1_OUT_N")
			(pinfunction "PETn1")
			(pintype "passive")
		)
		(pad "36" smd rect
			(at 0.345243 1.7 90)
			(size 0.35 3)
			(layers "F.Cu" "F.Mask")
			(net 29 "unconnected-(J2-NC-Pad36)")
			(pinfunction "NC")
			(pintype "no_connect")
		)
		(pad "37" smd rect
			(at 0.1 1.45 90)
			(size 0.35 2.5)
			(layers "B.Cu" "B.Mask")
			(net 40 "/Data_1_OUT_P")
			(pinfunction "PETp1")
			(pintype "passive")
		)
		(pad "38" smd rect
			(at -0.154757 1.7 90)
			(size 0.35 3)
			(layers "F.Cu" "F.Mask")
			(net 28 "unconnected-(J2-DEVSLP-Pad38)")
			(pinfunction "DEVSLP")
			(pintype "passive+no_connect")
		)
		(pad "39" smd rect
			(at -0.4 1.45 90)
			(size 0.35 2.5)
			(layers "B.Cu" "B.Mask")
			(net 60 "GND")
			(pinfunction "GND")
			(pintype "passive")
		)
		(pad "40" smd rect
			(at -0.654757 1.7 90)
			(size 0.35 3)
			(layers "F.Cu" "F.Mask")
			(net 27 "unconnected-(J2-NC-Pad40)")
			(pinfunction "NC")
			(pintype "no_connect")
		)
		(pad "41" smd rect
			(at -0.9 1.45 90)
			(size 0.35 2.5)
			(layers "B.Cu" "B.Mask")
			(net 34 "/Data_0_IN_N")
			(pinfunction "PERn0")
			(pintype "passive")
		)
		(pad "42" smd rect
			(at -1.154757 1.7 90)
			(size 0.35 3)
			(layers "F.Cu" "F.Mask")
			(net 26 "unconnected-(J2-NC-Pad42)")
			(pinfunction "NC")
			(pintype "no_connect")
		)
		(pad "43" smd rect
			(at -1.4 1.45 90)
			(size 0.35 2.5)
			(layers "B.Cu" "B.Mask")
			(net 35 "/Data_0_IN_P")
			(pinfunction "PERp0")
			(pintype "passive")
		)
		(pad "44" smd rect
			(at -1.654757 1.7 90)
			(size 0.35 3)
			(layers "F.Cu" "F.Mask")
			(net 25 "unconnected-(J2-NC-Pad44)")
			(pinfunction "NC")
			(pintype "no_connect")
		)
		(pad "45" smd rect
			(at -1.9 1.45 90)
			(size 0.35 2.5)
			(layers "B.Cu" "B.Mask")
			(net 60 "GND")
			(pinfunction "GND")
			(pintype "passive")
		)
		(pad "46" smd rect
			(at -2.154757 1.7 90)
			(size 0.35 3)
			(layers "F.Cu" "F.Mask")
			(net 24 "unconnected-(J2-NC-Pad46)")
			(pinfunction "NC")
			(pintype "no_connect")
		)
		(pad "47" smd rect
			(at -2.4 1.45 90)
			(size 0.35 2.5)
			(layers "B.Cu" "B.Mask")
			(net 37 "/Data_0_OUT_N")
			(pinfunction "PETn0")
			(pintype "passive")
		)
		(pad "48" smd rect
			(at -2.654757 1.7 90)
			(size 0.35 3)
			(layers "F.Cu" "F.Mask")
			(net 23 "unconnected-(J2-NC-Pad48)")
			(pinfunction "NC")
			(pintype "no_connect")
		)
		(pad "49" smd rect
			(at -2.9 1.45 90)
			(size 0.35 2.5)
			(layers "B.Cu" "B.Mask")
			(net 36 "/Data_0_OUT_P")
			(pinfunction "PETp0")
			(pintype "passive")
		)
		(pad "50" smd rect
			(at -3.154757 1.7 90)
			(size 0.35 3)
			(layers "F.Cu" "F.Mask")
			(net 59 "/PWRGD")
			(pinfunction "PERST#")
			(pintype "passive")
		)
		(pad "51" smd rect
			(at -3.4 1.45 90)
			(size 0.35 2.5)
			(layers "B.Cu" "B.Mask")
			(net 60 "GND")
			(pinfunction "GND")
			(pintype "passive")
		)
		(pad "52" smd rect
			(at -3.654757 1.7 90)
			(size 0.35 3)
			(layers "F.Cu" "F.Mask")
			(net 22 "Net-(J2-CLKREQ#)")
			(pinfunction "CLKREQ#")
			(pintype "passive")
		)
		(pad "53" smd rect
			(at -3.9 1.45 90)
			(size 0.35 2.5)
			(layers "B.Cu" "B.Mask")
			(net 33 "/REFCLK-")
			(pinfunction "REFCLKn")
			(pintype "passive")
		)
		(pad "54" smd rect
			(at -4.154757 1.7 90)
			(size 0.35 3)
			(layers "F.Cu" "F.Mask")
			(net 63 "/WAKE#")
			(pinfunction "PEWAKE#")
			(pintype "passive")
		)
		(pad "55" smd rect
			(at -4.4 1.45 90)
			(size 0.35 2.5)
			(layers "B.Cu" "B.Mask")
			(net 32 "/REFCLK+")
			(pinfunction "REFCLKp")
			(pintype "passive")
		)
		(pad "56" smd rect
			(at -4.654757 1.7 90)
			(size 0.35 3)
			(layers "F.Cu" "F.Mask")
			(net 21 "unconnected-(J2-NC-Pad56)")
			(pinfunction "NC")
			(pintype "no_connect")
		)
		(pad "57" smd rect
			(at -4.9 1.45 90)
			(size 0.35 2.5)
			(layers "B.Cu" "B.Mask")
			(net 60 "GND")
			(pinfunction "GND")
			(pintype "passive")
		)
		(pad "58" smd rect
			(at -5.154757 1.7 90)
			(size 0.35 3)
			(layers "F.Cu" "F.Mask")
			(net 20 "unconnected-(J2-NC-Pad58)")
			(pinfunction "NC")
			(pintype "no_connect")
		)
		(pad "67" smd rect
			(at -7.4 1.45 90)
			(size 0.35 2.5)
			(layers "B.Cu" "B.Mask")
			(net 19 "unconnected-(J2-NC-Pad67)")
			(pinfunction "NC")
			(pintype "no_connect")
		)
		(pad "68" smd rect
			(at -7.654757 1.7 90)
			(size 0.35 3)
			(layers "F.Cu" "F.Mask")
			(net 18 "unconnected-(J2-SUSCLK-Pad68)")
			(pinfunction "SUSCLK")
			(pintype "passive+no_connect")
		)
		(pad "69" smd rect
			(at -7.9 1.45 90)
			(size 0.35 2.5)
			(layers "B.Cu" "B.Mask")
			(net 17 "unconnected-(J2-PEDET-Pad69)")
			(pinfunction "PEDET")
			(pintype "passive+no_connect")
		)
		(pad "70" smd rect
			(at -8.154757 1.7 90)
			(size 0.35 3)
			(layers "F.Cu" "F.Mask")
			(net 31 "/+3V3")
			(pinfunction "3.3V")
			(pintype "passive")
		)
		(pad "71" smd rect
			(at -8.4 1.45 90)
			(size 0.35 2.5)
			(layers "B.Cu" "B.Mask")
			(net 60 "GND")
			(pinfunction "GND")
			(pintype "passive")
		)
		(pad "72" smd rect
			(at -8.654757 1.7 90)
			(size 0.35 3)
			(layers "F.Cu" "F.Mask")
			(net 31 "/+3V3")
			(pinfunction "3.3V")
			(pintype "passive")
		)
		(pad "73" smd rect
			(at -8.9 1.45 90)
			(size 0.35 2.5)
			(layers "B.Cu" "B.Mask")
			(net 60 "GND")
			(pinfunction "GND")
			(pintype "passive")
		)
		(pad "74" smd rect
			(at -9.154757 1.7 90)
			(size 0.35 3)
			(layers "F.Cu" "F.Mask")
			(net 31 "/+3V3")
			(pinfunction "3.3V")
			(pintype "passive")
		)
		(pad "75" smd rect
			(at -9.404757 1.45 90)
			(size 0.35 2.5)
			(layers "B.Cu" "B.Mask")
			(net 60 "GND")
			(pinfunction "GND")
			(pintype "passive")
		)
	)
	(footprint "antmicro-footprints:R_0402_1005Metric"
		(layer "B.Cu")
		(at 111.520059 104.427277 180)
		(descr "Resistor SMD 0402")
		(tags "resistor SMD 0402")
		(property "Reference" "R2"
			(at 0 -0.97 0)
			(layer "B.SilkS")
			(effects
				(font
					(size 0.7 0.7)
					(thickness 0.15)
				)
				(justify mirror)
			)
		)
		(property "Value" "R_0R_0402"
			(at 0 -1.17 0)
			(layer "B.Fab")
			(effects
				(font
					(size 1 1)
					(thickness 0.15)
				)
				(justify mirror)
			)
		)
		(property "Datasheet" "https://industrial.panasonic.com/cdbs/www-data/pdf/RDA0000/AOA0000C301.pdf"
			(at 0 0 180)
			(layer "F.Fab")
			(hide yes)
			(effects
				(font
					(size 1.27 1.27)
					(thickness 0.15)
				)
			)
		)
		(property "Description" "SMD Chip Resistor, Jumper, 0 ohm, 100 mW, 0402 [1005 Metric], Thick Film, General Purpose"
			(at 0 0 180)
			(layer "F.Fab")
			(hide yes)
			(effects
				(font
					(size 1.27 1.27)
					(thickness 0.15)
				)
			)
		)
		(property "Author" "Antmicro"
			(at 223.040118 208.854554 0)
			(layer "B.Fab")
			(hide yes)
			(effects
				(font
					(size 1 1)
					(thickness 0.15)
				)
				(justify mirror)
			)
		)
		(property "Current" "1A"
			(at 223.040118 208.854554 0)
			(layer "B.Fab")
			(hide yes)
			(effects
				(font
					(size 1 1)
					(thickness 0.15)
				)
				(justify mirror)
			)
		)
		(property "License" "Apache-2.0"
			(at 223.040118 208.854554 0)
			(layer "B.Fab")
			(hide yes)
			(effects
				(font
					(size 1 1)
					(thickness 0.15)
				)
				(justify mirror)
			)
		)
		(property "MPN" "ERJ2GE0R00X"
			(at 223.040118 208.854554 0)
			(layer "B.Fab")
			(hide yes)
			(effects
				(font
					(size 1 1)
					(thickness 0.15)
				)
				(justify mirror)
			)
		)
		(property "Manufacturer" "Panasonic"
			(at 223.040118 208.854554 0)
			(layer "B.Fab")
			(hide yes)
			(effects
				(font
					(size 1 1)
					(thickness 0.15)
				)
				(justify mirror)
			)
		)
		(property "Public" "False"
			(at 223.040118 208.854554 0)
			(layer "B.Fab")
			(hide yes)
			(effects
				(font
					(size 1 1)
					(thickness 0.15)
				)
				(justify mirror)
			)
		)
		(property "Tolerance" ""
			(at 223.040118 208.854554 0)
			(layer "B.Fab")
			(hide yes)
			(effects
				(font
					(size 1 1)
					(thickness 0.15)
				)
				(justify mirror)
			)
		)
		(property "Val" "0R"
			(at 223.040118 208.854554 0)
			(layer "B.Fab")
			(hide yes)
			(effects
				(font
					(size 1 1)
					(thickness 0.15)
				)
				(justify mirror)
			)
		)
		(sheetname "/")
		(sheetfile "m2-pcie-adapter.kicad_sch")
		(attr smd)
		(fp_rect
			(start -0.925 0.47)
			(end 0.925 -0.47)
			(stroke
				(width 0.05)
				(type default)
			)
			(fill no)
			(layer "B.CrtYd")
		)
		(fp_rect
			(start -0.5 0.25)
			(end 0.5 -0.25)
			(stroke
				(width 0.15)
				(type solid)
			)
			(fill no)
			(layer "B.Fab")
		)
		(fp_text user "${REFERENCE}"
			(at 0 0 0)
			(layer "B.Fab")
			(effects
				(font
					(size 0.25 0.25)
					(thickness 0.04)
				)
				(justify mirror)
			)
		)
		(pad "1" smd roundrect
			(at -0.48 0 180)
			(size 0.59 0.64)
			(layers "B.Cu" "B.Mask" "B.Paste")
			(roundrect_rratio 0.25)
			(net 22 "Net-(J2-CLKREQ#)")
			(pintype "passive")
		)
		(pad "2" smd roundrect
			(at 0.48 0 180)
			(size 0.59 0.64)
			(layers "B.Cu" "B.Mask" "B.Paste")
			(roundrect_rratio 0.25)
			(net 60 "GND")
			(pintype "passive")
		)
	)
	(footprint "antmicro-footprints:C_0402_1005Metric"
		(layer "B.Cu")
		(at 145.725059 112.367277 180)
		(descr "Capacitor SMD 0402")
		(tags "capacitor SMD 0402")
		(property "Reference" "C1"
			(at -1.575 -0.03 0)
			(layer "B.SilkS")
			(effects
				(font
					(size 0.7 0.7)
					(thickness 0.15)
				)
				(justify mirror)
			)
		)
		(property "Value" "C_100n_16V_X7R_0402"
			(at 0 -1.17 0)
			(layer "B.Fab")
			(effects
				(font
					(size 1 1)
					(thickness 0.15)
				)
				(justify mirror)
			)
		)
		(property "Datasheet" "https://www.kemet.com/en/us/capacitors/product/C0402C104J4RAC7411.html"
			(at 0 0 180)
			(layer "F.Fab")
			(hide yes)
			(effects
				(font
					(size 1.27 1.27)
					(thickness 0.15)
				)
			)
		)
		(property "Description" "SMD Multilayer Ceramic Capacitor, 100nF, 50V, 0402, ±5%, X7R"
			(at 0 0 180)
			(layer "F.Fab")
			(hide yes)
			(effects
				(font
					(size 1.27 1.27)
					(thickness 0.15)
				)
			)
		)
		(property "Author" "Antmicro"
			(at 291.450118 224.734554 0)
			(layer "B.Fab")
			(hide yes)
			(effects
				(font
					(size 1 1)
					(thickness 0.15)
				)
				(justify mirror)
			)
		)
		(property "Dielectric" "X7R"
			(at 291.450118 224.734554 0)
			(layer "B.Fab")
			(hide yes)
			(effects
				(font
					(size 1 1)
					(thickness 0.15)
				)
				(justify mirror)
			)
		)
		(property "License" "Apache-2.0"
			(at 291.450118 224.734554 0)
			(layer "B.Fab")
			(hide yes)
			(effects
				(font
					(size 1 1)
					(thickness 0.15)
				)
				(justify mirror)
			)
		)
		(property "MPN" "C0402C104J4RAC7411"
			(at 291.450118 224.734554 0)
			(layer "B.Fab")
			(hide yes)
			(effects
				(font
					(size 1 1)
					(thickness 0.15)
				)
				(justify mirror)
			)
		)
		(property "Manufacturer" "KEMET"
			(at 291.450118 224.734554 0)
			(layer "B.Fab")
			(hide yes)
			(effects
				(font
					(size 1 1)
					(thickness 0.15)
				)
				(justify mirror)
			)
		)
		(property "Val" "100n"
			(at 291.450118 224.734554 0)
			(layer "B.Fab")
			(hide yes)
			(effects
				(font
					(size 1 1)
					(thickness 0.15)
				)
				(justify mirror)
			)
		)
		(property "Voltage" "16V"
			(at 291.450118 224.734554 0)
			(layer "B.Fab")
			(hide yes)
			(effects
				(font
					(size 1 1)
					(thickness 0.15)
				)
				(justify mirror)
			)
		)
		(sheetname "/")
		(sheetfile "m2-pcie-adapter.kicad_sch")
		(attr smd)
		(fp_rect
			(start -0.925 0.47)
			(end 0.925 -0.47)
			(stroke
				(width 0.05)
				(type default)
			)
			(fill no)
			(layer "B.CrtYd")
		)
		(fp_line
			(start 0.504 0.25)
			(end 0.504 -0.248)
			(stroke
				(width 0.15)
				(type solid)
			)
			(layer "B.Fab")
		)
		(fp_line
			(start 0.504 -0.248)
			(end -0.494 -0.248)
			(stroke
				(width 0.15)
				(type solid)
			)
			(layer "B.Fab")
		)
		(fp_line
			(start -0.494 0.25)
			(end 0.504 0.25)
			(stroke
				(width 0.15)
				(type solid)
			)
			(layer "B.Fab")
		)
		(fp_line
			(start -0.494 -0.248)
			(end -0.494 0.25)
			(stroke
				(width 0.15)
				(type solid)
			)
			(layer "B.Fab")
		)
		(fp_text user "${REFERENCE}"
			(at 0 0 0)
			(layer "B.Fab")
			(effects
				(font
					(size 0.25 0.25)
					(thickness 0.04)
				)
				(justify mirror)
			)
		)
		(pad "1" smd roundrect
			(at -0.48 0 180)
			(size 0.59 0.64)
			(layers "B.Cu" "B.Mask" "B.Paste")
			(roundrect_rratio 0.25)
			(net 30 "+12V")
			(pintype "passive")
		)
		(pad "2" smd roundrect
			(at 0.48 0 180)
			(size 0.59 0.64)
			(layers "B.Cu" "B.Mask" "B.Paste")
			(roundrect_rratio 0.25)
			(net 60 "GND")
			(pintype "passive")
		)
	)
	(footprint "antmicro-footprints:C_0402_1005Metric"
		(layer "B.Cu")
		(at 142.300059 111.197277)
		(descr "Capacitor SMD 0402")
		(tags "capacitor SMD 0402")
		(property "Reference" "C4"
			(at 0.1 -2.65 0)
			(layer "B.SilkS")
			(effects
				(font
					(size 0.7 0.7)
					(thickness 0.15)
				)
				(justify mirror)
			)
		)
		(property "Value" "C_100n_16V_X7R_0402"
			(at 0 -1.17 0)
			(layer "B.Fab")
			(effects
				(font
					(size 1 1)
					(thickness 0.15)
				)
				(justify mirror)
			)
		)
		(property "Datasheet" "https://www.kemet.com/en/us/capacitors/product/C0402C104J4RAC7411.html"
			(at 0 0 0)
			(layer "F.Fab")
			(hide yes)
			(effects
				(font
					(size 1.27 1.27)
					(thickness 0.15)
				)
			)
		)
		(property "Description" "SMD Multilayer Ceramic Capacitor, 100nF, 50V, 0402, ±5%, X7R"
			(at 0 0 0)
			(layer "F.Fab")
			(hide yes)
			(effects
				(font
					(size 1.27 1.27)
					(thickness 0.15)
				)
			)
		)
		(property "Author" "Antmicro"
			(at 0 0 0)
			(layer "B.Fab")
			(hide yes)
			(effects
				(font
					(size 1 1)
					(thickness 0.15)
				)
				(justify mirror)
			)
		)
		(property "Dielectric" "X7R"
			(at 0 0 0)
			(layer "B.Fab")
			(hide yes)
			(effects
				(font
					(size 1 1)
					(thickness 0.15)
				)
				(justify mirror)
			)
		)
		(property "License" "Apache-2.0"
			(at 0 0 0)
			(layer "B.Fab")
			(hide yes)
			(effects
				(font
					(size 1 1)
					(thickness 0.15)
				)
				(justify mirror)
			)
		)
		(property "MPN" "C0402C104J4RAC7411"
			(at 0 0 0)
			(layer "B.Fab")
			(hide yes)
			(effects
				(font
					(size 1 1)
					(thickness 0.15)
				)
				(justify mirror)
			)
		)
		(property "Manufacturer" "KEMET"
			(at 0 0 0)
			(layer "B.Fab")
			(hide yes)
			(effects
				(font
					(size 1 1)
					(thickness 0.15)
				)
				(justify mirror)
			)
		)
		(property "Val" "100n"
			(at 0 0 0)
			(layer "B.Fab")
			(hide yes)
			(effects
				(font
					(size 1 1)
					(thickness 0.15)
				)
				(justify mirror)
			)
		)
		(property "Voltage" "16V"
			(at 0 0 0)
			(layer "B.Fab")
			(hide yes)
			(effects
				(font
					(size 1 1)
					(thickness 0.15)
				)
				(justify mirror)
			)
		)
		(sheetname "/")
		(sheetfile "m2-pcie-adapter.kicad_sch")
		(attr smd)
		(fp_rect
			(start -0.925 0.47)
			(end 0.925 -0.47)
			(stroke
				(width 0.05)
				(type default)
			)
			(fill no)
			(layer "B.CrtYd")
		)
		(fp_line
			(start -0.494 -0.248)
			(end -0.494 0.25)
			(stroke
				(width 0.15)
				(type solid)
			)
			(layer "B.Fab")
		)
		(fp_line
			(start -0.494 0.25)
			(end 0.504 0.25)
			(stroke
				(width 0.15)
				(type solid)
			)
			(layer "B.Fab")
		)
		(fp_line
			(start 0.504 -0.248)
			(end -0.494 -0.248)
			(stroke
				(width 0.15)
				(type solid)
			)
			(layer "B.Fab")
		)
		(fp_line
			(start 0.504 0.25)
			(end 0.504 -0.248)
			(stroke
				(width 0.15)
				(type solid)
			)
			(layer "B.Fab")
		)
		(fp_text user "${REFERENCE}"
			(at 0 0 0)
			(layer "B.Fab")
			(effects
				(font
					(size 0.25 0.25)
					(thickness 0.04)
				)
				(justify mirror)
			)
		)
		(pad "1" smd roundrect
			(at -0.48 0)
			(size 0.59 0.64)
			(layers "B.Cu" "B.Mask" "B.Paste")
			(roundrect_rratio 0.25)
			(net 31 "/+3V3")
			(pintype "passive")
		)
		(pad "2" smd roundrect
			(at 0.48 0)
			(size 0.59 0.64)
			(layers "B.Cu" "B.Mask" "B.Paste")
			(roundrect_rratio 0.25)
			(net 60 "GND")
			(pintype "passive")
		)
	)
	(footprint "antmicro-footprints:R_0402_1005Metric"
		(layer "B.Cu")
		(at 138.000059 106.947277 -90)
		(descr "Resistor SMD 0402")
		(tags "resistor SMD 0402")
		(property "Reference" "R1"
			(at 0 1 90)
			(layer "B.SilkS")
			(effects
				(font
					(size 0.7 0.7)
					(thickness 0.15)
				)
				(justify mirror)
			)
		)
		(property "Value" "R_0R_0402"
			(at 0 -1.17 90)
			(layer "B.Fab")
			(effects
				(font
					(size 1 1)
					(thickness 0.15)
				)
				(justify mirror)
			)
		)
		(property "Datasheet" "https://industrial.panasonic.com/cdbs/www-data/pdf/RDA0000/AOA0000C301.pdf"
			(at 0 0 270)
			(layer "F.Fab")
			(hide yes)
			(effects
				(font
					(size 1.27 1.27)
					(thickness 0.15)
				)
			)
		)
		(property "Description" "SMD Chip Resistor, Jumper, 0 ohm, 100 mW, 0402 [1005 Metric], Thick Film, General Purpose"
			(at 0 0 270)
			(layer "F.Fab")
			(hide yes)
			(effects
				(font
					(size 1.27 1.27)
					(thickness 0.15)
				)
			)
		)
		(property "Author" "Antmicro"
			(at 31.052782 244.947336 0)
			(layer "B.Fab")
			(hide yes)
			(effects
				(font
					(size 1 1)
					(thickness 0.15)
				)
				(justify mirror)
			)
		)
		(property "Current" "1A"
			(at 31.052782 244.947336 0)
			(layer "B.Fab")
			(hide yes)
			(effects
				(font
					(size 1 1)
					(thickness 0.15)
				)
				(justify mirror)
			)
		)
		(property "License" "Apache-2.0"
			(at 31.052782 244.947336 0)
			(layer "B.Fab")
			(hide yes)
			(effects
				(font
					(size 1 1)
					(thickness 0.15)
				)
				(justify mirror)
			)
		)
		(property "MPN" "ERJ2GE0R00X"
			(at 31.052782 244.947336 0)
			(layer "B.Fab")
			(hide yes)
			(effects
				(font
					(size 1 1)
					(thickness 0.15)
				)
				(justify mirror)
			)
		)
		(property "Manufacturer" "Panasonic"
			(at 31.052782 244.947336 0)
			(layer "B.Fab")
			(hide yes)
			(effects
				(font
					(size 1 1)
					(thickness 0.15)
				)
				(justify mirror)
			)
		)
		(property "Public" "False"
			(at 31.052782 244.947336 0)
			(layer "B.Fab")
			(hide yes)
			(effects
				(font
					(size 1 1)
					(thickness 0.15)
				)
				(justify mirror)
			)
		)
		(property "Tolerance" ""
			(at 31.052782 244.947336 0)
			(layer "B.Fab")
			(hide yes)
			(effects
				(font
					(size 1 1)
					(thickness 0.15)
				)
				(justify mirror)
			)
		)
		(property "Val" "0R"
			(at 31.052782 244.947336 0)
			(layer "B.Fab")
			(hide yes)
			(effects
				(font
					(size 1 1)
					(thickness 0.15)
				)
				(justify mirror)
			)
		)
		(sheetname "/")
		(sheetfile "m2-pcie-adapter.kicad_sch")
		(attr smd)
		(fp_rect
			(start -0.925 0.47)
			(end 0.925 -0.47)
			(stroke
				(width 0.05)
				(type default)
			)
			(fill no)
			(layer "B.CrtYd")
		)
		(fp_rect
			(start -0.5 0.25)
			(end 0.5 -0.25)
			(stroke
				(width 0.15)
				(type solid)
			)
			(fill no)
			(layer "B.Fab")
		)
		(pad "1" smd roundrect
			(at -0.48 0 270)
			(size 0.59 0.64)
			(layers "B.Cu" "B.Mask" "B.Paste")
			(roundrect_rratio 0.25)
			(net 31 "/+3V3")
			(pintype "passive")
		)
		(pad "2" smd roundrect
			(at 0.48 0 270)
			(size 0.59 0.64)
			(layers "B.Cu" "B.Mask" "B.Paste")
			(roundrect_rratio 0.25)
			(net 62 "/+3V3_AUX")
			(pintype "passive")
		)
	)
	(footprint "antmicro-footprints:C_0603_1608Metric"
		(layer "B.Cu")
		(at 113.890059 88.567277)
		(descr "Capacitor SMD 0603")
		(tags "capacitor 0603")
		(property "Reference" "C7"
			(at 0.01 1.29 0)
			(layer "B.SilkS")
			(effects
				(font
					(size 0.7 0.7)
					(thickness 0.15)
				)
				(justify mirror)
			)
		)
		(property "Value" "C_1u_0603"
			(at 0 -1.9 0)
			(layer "B.Fab")
			(effects
				(font
					(size 1 1)
					(thickness 0.15)
				)
				(justify mirror)
			)
		)
		(property "Datasheet" "https://spicat.kyocera-avx.com/product/mlcc/chartview/0603YD105KAT2A/"
			(at 0 0 0)
			(layer "F.Fab")
			(hide yes)
			(effects
				(font
					(size 1.27 1.27)
					(thickness 0.15)
				)
			)
		)
		(property "Description" "SMD Multilayer Ceramic Capacitor, 1 µF, 16 V, 0603 [1608 Metric], ± 10%, X5R, AVX 0603 MLCC"
			(at 0 0 0)
			(layer "F.Fab")
			(hide yes)
			(effects
				(font
					(size 1.27 1.27)
					(thickness 0.15)
				)
			)
		)
		(property "Author" "Antmicro"
			(at 0 0 0)
			(layer "B.Fab")
			(hide yes)
			(effects
				(font
					(size 1 1)
					(thickness 0.15)
				)
				(justify mirror)
			)
		)
		(property "Dielectric" ""
			(at 0 0 0)
			(layer "B.Fab")
			(hide yes)
			(effects
				(font
					(size 1 1)
					(thickness 0.15)
				)
				(justify mirror)
			)
		)
		(property "License" "Apache-2.0"
			(at 0 0 0)
			(layer "B.Fab")
			(hide yes)
			(effects
				(font
					(size 1 1)
					(thickness 0.15)
				)
				(justify mirror)
			)
		)
		(property "MPN" "0603YD105KAT2A"
			(at 0 0 0)
			(layer "B.Fab")
			(hide yes)
			(effects
				(font
					(size 1 1)
					(thickness 0.15)
				)
				(justify mirror)
			)
		)
		(property "Manufacturer" "KYOCERA AVX"
			(at 0 0 0)
			(layer "B.Fab")
			(hide yes)
			(effects
				(font
					(size 1 1)
					(thickness 0.15)
				)
				(justify mirror)
			)
		)
		(property "Public" "False"
			(at 0 0 0)
			(layer "B.Fab")
			(hide yes)
			(effects
				(font
					(size 1 1)
					(thickness 0.15)
				)
				(justify mirror)
			)
		)
		(property "Val" "1u"
			(at 0 0 0)
			(layer "B.Fab")
			(hide yes)
			(effects
				(font
					(size 1 1)
					(thickness 0.15)
				)
				(justify mirror)
			)
		)
		(property "Voltage" ""
			(at 0 0 0)
			(layer "B.Fab")
			(hide yes)
			(effects
				(font
					(size 1 1)
					(thickness 0.15)
				)
				(justify mirror)
			)
		)
		(sheetname "/")
		(sheetfile "m2-pcie-adapter.kicad_sch")
		(attr smd)
		(fp_line
			(start -0.15 -0.4)
			(end 0.15 -0.4)
			(stroke
				(width 0.15)
				(type solid)
			)
			(layer "B.SilkS")
		)
		(fp_line
			(start -0.15 0.4)
			(end 0.15 0.4)
			(stroke
				(width 0.15)
				(type solid)
			)
			(layer "B.SilkS")
		)
		(fp_rect
			(start -1.25 0.65)
			(end 1.25 -0.65)
			(stroke
				(width 0.05)
				(type solid)
			)
			(fill no)
			(layer "B.CrtYd")
		)
		(fp_rect
			(start -0.8 0.4)
			(end 0.8 -0.4)
			(stroke
				(width 0.15)
				(type solid)
			)
			(fill no)
			(layer "B.Fab")
		)
		(pad "1" smd roundrect
			(at -0.7 0)
			(size 0.8 1)
			(layers "B.Cu" "B.Mask" "B.Paste")
			(roundrect_rratio 0.2)
			(net 31 "/+3V3")
			(pintype "passive")
		)
		(pad "2" smd roundrect
			(at 0.7 0)
			(size 0.8 1)
			(layers "B.Cu" "B.Mask" "B.Paste")
			(roundrect_rratio 0.2)
			(net 60 "GND")
			(pintype "passive")
		)
	)
	(footprint "antmicro-footprints:C_0603_1608Metric"
		(layer "B.Cu")
		(at 145.510059 114.017277 180)
		(descr "Capacitor SMD 0603")
		(tags "capacitor 0603")
		(property "Reference" "C2"
			(at -1.89 -0.01 0)
			(layer "B.SilkS")
			(effects
				(font
					(size 0.7 0.7)
					(thickness 0.15)
				)
				(justify mirror)
			)
		)
		(property "Value" "C_1u_0603"
			(at 0 -1.9 0)
			(layer "B.Fab")
			(effects
				(font
					(size 1 1)
					(thickness 0.15)
				)
				(justify mirror)
			)
		)
		(property "Datasheet" "https://spicat.kyocera-avx.com/product/mlcc/chartview/0603YD105KAT2A/"
			(at 0 0 180)
			(layer "F.Fab")
			(hide yes)
			(effects
				(font
					(size 1.27 1.27)
					(thickness 0.15)
				)
			)
		)
		(property "Description" "SMD Multilayer Ceramic Capacitor, 1 µF, 16 V, 0603 [1608 Metric], ± 10%, X5R, AVX 0603 MLCC"
			(at 0 0 180)
			(layer "F.Fab")
			(hide yes)
			(effects
				(font
					(size 1.27 1.27)
					(thickness 0.15)
				)
			)
		)
		(property "Author" "Antmicro"
			(at 291.020118 228.034554 0)
			(layer "B.Fab")
			(hide yes)
			(effects
				(font
					(size 1 1)
					(thickness 0.15)
				)
				(justify mirror)
			)
		)
		(property "Dielectric" ""
			(at 291.020118 228.034554 0)
			(layer "B.Fab")
			(hide yes)
			(effects
				(font
					(size 1 1)
					(thickness 0.15)
				)
				(justify mirror)
			)
		)
		(property "License" "Apache-2.0"
			(at 291.020118 228.034554 0)
			(layer "B.Fab")
			(hide yes)
			(effects
				(font
					(size 1 1)
					(thickness 0.15)
				)
				(justify mirror)
			)
		)
		(property "MPN" "0603YD105KAT2A"
			(at 291.020118 228.034554 0)
			(layer "B.Fab")
			(hide yes)
			(effects
				(font
					(size 1 1)
					(thickness 0.15)
				)
				(justify mirror)
			)
		)
		(property "Manufacturer" "KYOCERA AVX"
			(at 291.020118 228.034554 0)
			(layer "B.Fab")
			(hide yes)
			(effects
				(font
					(size 1 1)
					(thickness 0.15)
				)
				(justify mirror)
			)
		)
		(property "Public" "False"
			(at 291.020118 228.034554 0)
			(layer "B.Fab")
			(hide yes)
			(effects
				(font
					(size 1 1)
					(thickness 0.15)
				)
				(justify mirror)
			)
		)
		(property "Val" "1u"
			(at 291.020118 228.034554 0)
			(layer "B.Fab")
			(hide yes)
			(effects
				(font
					(size 1 1)
					(thickness 0.15)
				)
				(justify mirror)
			)
		)
		(property "Voltage" ""
			(at 291.020118 228.034554 0)
			(layer "B.Fab")
			(hide yes)
			(effects
				(font
					(size 1 1)
					(thickness 0.15)
				)
				(justify mirror)
			)
		)
		(sheetname "/")
		(sheetfile "m2-pcie-adapter.kicad_sch")
		(attr smd)
		(fp_line
			(start -0.15 0.4)
			(end 0.15 0.4)
			(stroke
				(width 0.15)
				(type solid)
			)
			(layer "B.SilkS")
		)
		(fp_line
			(start -0.15 -0.4)
			(end 0.15 -0.4)
			(stroke
				(width 0.15)
				(type solid)
			)
			(layer "B.SilkS")
		)
		(fp_rect
			(start -1.25 0.65)
			(end 1.25 -0.65)
			(stroke
				(width 0.05)
				(type solid)
			)
			(fill no)
			(layer "B.CrtYd")
		)
		(fp_rect
			(start -0.8 0.4)
			(end 0.8 -0.4)
			(stroke
				(width 0.15)
				(type solid)
			)
			(fill no)
			(layer "B.Fab")
		)
		(pad "1" smd roundrect
			(at -0.7 0 180)
			(size 0.8 1)
			(layers "B.Cu" "B.Mask" "B.Paste")
			(roundrect_rratio 0.2)
			(net 30 "+12V")
			(pintype "passive")
		)
		(pad "2" smd roundrect
			(at 0.7 0 180)
			(size 0.8 1)
			(layers "B.Cu" "B.Mask" "B.Paste")
			(roundrect_rratio 0.2)
			(net 60 "GND")
			(pintype "passive")
		)
	)
	(footprint "antmicro-footprints:C_0603_1608Metric"
		(layer "B.Cu")
		(at 137.320059 114.017277 180)
		(descr "Capacitor SMD 0603")
		(tags "capacitor 0603")
		(property "Reference" "C6"
			(at 1.82 -0.02 0)
			(layer "B.SilkS")
			(effects
				(font
					(size 0.7 0.7)
					(thickness 0.15)
				)
				(justify mirror)
			)
		)
		(property "Value" "C_1u_0603"
			(at 0 -1.9 0)
			(layer "B.Fab")
			(effects
				(font
					(size 1 1)
					(thickness 0.15)
				)
				(justify mirror)
			)
		)
		(property "Datasheet" "https://spicat.kyocera-avx.com/product/mlcc/chartview/0603YD105KAT2A/"
			(at 0 0 180)
			(layer "F.Fab")
			(hide yes)
			(effects
				(font
					(size 1.27 1.27)
					(thickness 0.15)
				)
			)
		)
		(property "Description" "SMD Multilayer Ceramic Capacitor, 1 µF, 16 V, 0603 [1608 Metric], ± 10%, X5R, AVX 0603 MLCC"
			(at 0 0 180)
			(layer "F.Fab")
			(hide yes)
			(effects
				(font
					(size 1.27 1.27)
					(thickness 0.15)
				)
			)
		)
		(property "Author" "Antmicro"
			(at 274.640118 228.034554 0)
			(layer "B.Fab")
			(hide yes)
			(effects
				(font
					(size 1 1)
					(thickness 0.15)
				)
				(justify mirror)
			)
		)
		(property "Dielectric" ""
			(at 274.640118 228.034554 0)
			(layer "B.Fab")
			(hide yes)
			(effects
				(font
					(size 1 1)
					(thickness 0.15)
				)
				(justify mirror)
			)
		)
		(property "License" "Apache-2.0"
			(at 274.640118 228.034554 0)
			(layer "B.Fab")
			(hide yes)
			(effects
				(font
					(size 1 1)
					(thickness 0.15)
				)
				(justify mirror)
			)
		)
		(property "MPN" "0603YD105KAT2A"
			(at 274.640118 228.034554 0)
			(layer "B.Fab")
			(hide yes)
			(effects
				(font
					(size 1 1)
					(thickness 0.15)
				)
				(justify mirror)
			)
		)
		(property "Manufacturer" "KYOCERA AVX"
			(at 274.640118 228.034554 0)
			(layer "B.Fab")
			(hide yes)
			(effects
				(font
					(size 1 1)
					(thickness 0.15)
				)
				(justify mirror)
			)
		)
		(property "Public" "False"
			(at 274.640118 228.034554 0)
			(layer "B.Fab")
			(hide yes)
			(effects
				(font
					(size 1 1)
					(thickness 0.15)
				)
				(justify mirror)
			)
		)
		(property "Val" "1u"
			(at 274.640118 228.034554 0)
			(layer "B.Fab")
			(hide yes)
			(effects
				(font
					(size 1 1)
					(thickness 0.15)
				)
				(justify mirror)
			)
		)
		(property "Voltage" ""
			(at 274.640118 228.034554 0)
			(layer "B.Fab")
			(hide yes)
			(effects
				(font
					(size 1 1)
					(thickness 0.15)
				)
				(justify mirror)
			)
		)
		(sheetname "/")
		(sheetfile "m2-pcie-adapter.kicad_sch")
		(attr smd)
		(fp_line
			(start -0.15 0.4)
			(end 0.15 0.4)
			(stroke
				(width 0.15)
				(type solid)
			)
			(layer "B.SilkS")
		)
		(fp_line
			(start -0.15 -0.4)
			(end 0.15 -0.4)
			(stroke
				(width 0.15)
				(type solid)
			)
			(layer "B.SilkS")
		)
		(fp_rect
			(start -1.25 0.65)
			(end 1.25 -0.65)
			(stroke
				(width 0.05)
				(type solid)
			)
			(fill no)
			(layer "B.CrtYd")
		)
		(fp_rect
			(start -0.8 0.4)
			(end 0.8 -0.4)
			(stroke
				(width 0.15)
				(type solid)
			)
			(fill no)
			(layer "B.Fab")
		)
		(pad "1" smd roundrect
			(at -0.7 0 180)
			(size 0.8 1)
			(layers "B.Cu" "B.Mask" "B.Paste")
			(roundrect_rratio 0.2)
			(net 62 "/+3V3_AUX")
			(pintype "passive")
		)
		(pad "2" smd roundrect
			(at 0.7 0 180)
			(size 0.8 1)
			(layers "B.Cu" "B.Mask" "B.Paste")
			(roundrect_rratio 0.2)
			(net 60 "GND")
			(pintype "passive")
		)
	)
	(footprint "antmicro-footprints:C_0603_1608Metric"
		(layer "B.Cu")
		(at 142.500059 114.017277)
		(descr "Capacitor SMD 0603")
		(tags "capacitor 0603")
		(property "Reference" "C3"
			(at -0.1 -3.67 0)
			(layer "B.SilkS")
			(effects
				(font
					(size 0.7 0.7)
					(thickness 0.15)
				)
				(justify mirror)
			)
		)
		(property "Value" "C_1u_0603"
			(at 0 -1.9 0)
			(layer "B.Fab")
			(effects
				(font
					(size 1 1)
					(thickness 0.15)
				)
				(justify mirror)
			)
		)
		(property "Datasheet" "https://spicat.kyocera-avx.com/product/mlcc/chartview/0603YD105KAT2A/"
			(at 0 0 0)
			(layer "F.Fab")
			(hide yes)
			(effects
				(font
					(size 1.27 1.27)
					(thickness 0.15)
				)
			)
		)
		(property "Description" "SMD Multilayer Ceramic Capacitor, 1 µF, 16 V, 0603 [1608 Metric], ± 10%, X5R, AVX 0603 MLCC"
			(at 0 0 0)
			(layer "F.Fab")
			(hide yes)
			(effects
				(font
					(size 1.27 1.27)
					(thickness 0.15)
				)
			)
		)
		(property "Author" "Antmicro"
			(at 0 0 0)
			(layer "B.Fab")
			(hide yes)
			(effects
				(font
					(size 1 1)
					(thickness 0.15)
				)
				(justify mirror)
			)
		)
		(property "Dielectric" ""
			(at 0 0 0)
			(layer "B.Fab")
			(hide yes)
			(effects
				(font
					(size 1 1)
					(thickness 0.15)
				)
				(justify mirror)
			)
		)
		(property "License" "Apache-2.0"
			(at 0 0 0)
			(layer "B.Fab")
			(hide yes)
			(effects
				(font
					(size 1 1)
					(thickness 0.15)
				)
				(justify mirror)
			)
		)
		(property "MPN" "0603YD105KAT2A"
			(at 0 0 0)
			(layer "B.Fab")
			(hide yes)
			(effects
				(font
					(size 1 1)
					(thickness 0.15)
				)
				(justify mirror)
			)
		)
		(property "Manufacturer" "KYOCERA AVX"
			(at 0 0 0)
			(layer "B.Fab")
			(hide yes)
			(effects
				(font
					(size 1 1)
					(thickness 0.15)
				)
				(justify mirror)
			)
		)
		(property "Public" "False"
			(at 0 0 0)
			(layer "B.Fab")
			(hide yes)
			(effects
				(font
					(size 1 1)
					(thickness 0.15)
				)
				(justify mirror)
			)
		)
		(property "Val" "1u"
			(at 0 0 0)
			(layer "B.Fab")
			(hide yes)
			(effects
				(font
					(size 1 1)
					(thickness 0.15)
				)
				(justify mirror)
			)
		)
		(property "Voltage" ""
			(at 0 0 0)
			(layer "B.Fab")
			(hide yes)
			(effects
				(font
					(size 1 1)
					(thickness 0.15)
				)
				(justify mirror)
			)
		)
		(sheetname "/")
		(sheetfile "m2-pcie-adapter.kicad_sch")
		(attr smd)
		(fp_line
			(start -0.15 -0.4)
			(end 0.15 -0.4)
			(stroke
				(width 0.15)
				(type solid)
			)
			(layer "B.SilkS")
		)
		(fp_line
			(start -0.15 0.4)
			(end 0.15 0.4)
			(stroke
				(width 0.15)
				(type solid)
			)
			(layer "B.SilkS")
		)
		(fp_rect
			(start -1.25 0.65)
			(end 1.25 -0.65)
			(stroke
				(width 0.05)
				(type solid)
			)
			(fill no)
			(layer "B.CrtYd")
		)
		(fp_rect
			(start -0.8 0.4)
			(end 0.8 -0.4)
			(stroke
				(width 0.15)
				(type solid)
			)
			(fill no)
			(layer "B.Fab")
		)
		(pad "1" smd roundrect
			(at -0.7 0)
			(size 0.8 1)
			(layers "B.Cu" "B.Mask" "B.Paste")
			(roundrect_rratio 0.2)
			(net 31 "/+3V3")
			(pintype "passive")
		)
		(pad "2" smd roundrect
			(at 0.7 0)
			(size 0.8 1)
			(layers "B.Cu" "B.Mask" "B.Paste")
			(roundrect_rratio 0.2)
			(net 60 "GND")
			(pintype "passive")
		)
	)
	(footprint "antmicro-footprints:Conn_Molex_KK_1x4_22-05-3041_Horizontal"
		(layer "B.Cu")
		(at 175.590059 96.137277 180)
		(property "Reference" "J3"
			(at 0 1.95 0)
			(layer "B.SilkS")
			(effects
				(font
					(size 0.7 0.7)
					(thickness 0.15)
				)
				(justify left bottom mirror)
			)
		)
		(property "Value" "Molex_KK_1x4_22-05-3041_Horizontal"
			(at 0 -14 0)
			(layer "B.Fab")
			(effects
				(font
					(size 0.7 0.7)
					(thickness 0.15)
				)
				(justify left bottom mirror)
			)
		)
		(property "Datasheet" "https://www.molex.com/content/dam/molex/molex-dot-com/products/automated/en-us/salesdrawingpdf/747/7478/022053041_sd.pdf?inline"
			(at 0 0 180)
			(layer "F.Fab")
			(hide yes)
			(effects
				(font
					(size 1.27 1.27)
					(thickness 0.15)
				)
			)
		)
		(property "Description" "Connector Header, THT,  4x1"
			(at 0 0 180)
			(layer "F.Fab")
			(hide yes)
			(effects
				(font
					(size 1.27 1.27)
					(thickness 0.15)
				)
			)
		)
		(property "Author" "Antmicro"
			(at 351.180118 192.274554 0)
			(layer "B.Fab")
			(hide yes)
			(effects
				(font
					(size 1 1)
					(thickness 0.15)
				)
				(justify mirror)
			)
		)
		(property "License" "Apache-2.0"
			(at 351.180118 192.274554 0)
			(layer "B.Fab")
			(hide yes)
			(effects
				(font
					(size 1 1)
					(thickness 0.15)
				)
				(justify mirror)
			)
		)
		(property "MPN" "22-05-3041"
			(at 351.180118 192.274554 0)
			(layer "B.Fab")
			(hide yes)
			(effects
				(font
					(size 1 1)
					(thickness 0.15)
				)
				(justify mirror)
			)
		)
		(property "Manufacturer" "Molex"
			(at 351.180118 192.274554 0)
			(layer "B.Fab")
			(hide yes)
			(effects
				(font
					(size 1 1)
					(thickness 0.15)
				)
				(justify mirror)
			)
		)
		(sheetname "/")
		(sheetfile "m2-pcie-adapter.kicad_sch")
		(attr through_hole dnp)
		(fp_line
			(start 8.9 1.55)
			(end 8.9 1.05)
			(stroke
				(width 0.15)
				(type solid)
			)
			(layer "B.SilkS")
		)
		(fp_line
			(start 8.9 1.55)
			(end 8.4 1.55)
			(stroke
				(width 0.15)
				(type solid)
			)
			(layer "B.SilkS")
		)
		(fp_line
			(start -1.275 1.525)
			(end -0.775 1.525)
			(stroke
				(width 0.15)
				(type solid)
			)
			(layer "B.SilkS")
		)
		(fp_line
			(start -1.275 1.525)
			(end -1.275 1.025)
			(stroke
				(width 0.15)
				(type solid)
			)
			(layer "B.SilkS")
		)
		(fp_line
			(start -1.3 -3.3)
			(end -0.8 -3.3)
			(stroke
				(width 0.15)
				(type solid)
			)
			(layer "B.SilkS")
		)
		(fp_line
			(start -1.3 -3.3)
			(end -1.3 -2.8)
			(stroke
				(width 0.15)
				(type solid)
			)
			(layer "B.SilkS")
		)
		(fp_circle
			(center -0.9 -1.8)
			(end -0.85 -1.8)
			(stroke
				(width 0.15)
				(type solid)
			)
			(fill yes)
			(layer "B.SilkS")
		)
		(fp_rect
			(start -1.6 1.7)
			(end 9.2 -12.94)
			(stroke
				(width 0.05)
				(type solid)
			)
			(fill no)
			(layer "B.CrtYd")
		)
		(fp_line
			(start 8.81 1.425)
			(end 8.81 -3.17)
			(stroke
				(width 0.15)
				(type solid)
			)
			(layer "B.Fab")
		)
		(fp_line
			(start -1.2 1.425)
			(end -1.2 -3.17)
			(stroke
				(width 0.15)
				(type solid)
			)
			(layer "B.Fab")
		)
		(fp_line
			(start -1.2 -3.17)
			(end 8.81 -3.17)
			(stroke
				(width 0.15)
				(type solid)
			)
			(layer "B.Fab")
		)
		(fp_line
			(start -1.225 1.425)
			(end 8.785 1.425)
			(stroke
				(width 0.15)
				(type solid)
			)
			(layer "B.Fab")
		)
		(pad "1" thru_hole circle
			(at 0 0 180)
			(size 2.02 2.02)
			(drill 1.02)
			(layers "*.Cu" "*.Mask")
			(remove_unused_layers no)
			(net 30 "+12V")
			(pintype "passive")
		)
		(pad "2" thru_hole circle
			(at 2.54 0 180)
			(size 2.02 2.02)
			(drill 1.02)
			(layers "*.Cu" "*.Mask")
			(remove_unused_layers no)
			(net 60 "GND")
			(pintype "passive")
		)
		(pad "3" thru_hole circle
			(at 5.08 0 180)
			(size 2.02 2.02)
			(drill 1.02)
			(layers "*.Cu" "*.Mask")
			(remove_unused_layers no)
			(net 60 "GND")
			(pintype "passive")
		)
		(pad "4" thru_hole circle
			(at 7.62 0 180)
			(size 2.02 2.02)
			(drill 1.02)
			(layers "*.Cu" "*.Mask")
			(remove_unused_layers no)
			(net 61 "+5V")
			(pintype "passive")
		)
	)
	(footprint "antmicro-footprints:C_0603_1608Metric"
		(layer "B.Cu")
		(at 142.500059 112.497277)
		(descr "Capacitor SMD 0603")
		(tags "capacitor 0603")
		(property "Reference" "C8"
			(at -0.1 -3.05 0)
			(layer "B.SilkS")
			(effects
				(font
					(size 0.7 0.7)
					(thickness 0.15)
				)
				(justify mirror)
			)
		)
		(property "Value" "C_1u_0603"
			(at 0 -1.9 0)
			(layer "B.Fab")
			(effects
				(font
					(size 1 1)
					(thickness 0.15)
				)
				(justify mirror)
			)
		)
		(property "Datasheet" "https://spicat.kyocera-avx.com/product/mlcc/chartview/0603YD105KAT2A/"
			(at 0 0 0)
			(layer "F.Fab")
			(hide yes)
			(effects
				(font
					(size 1.27 1.27)
					(thickness 0.15)
				)
			)
		)
		(property "Description" "SMD Multilayer Ceramic Capacitor, 1 µF, 16 V, 0603 [1608 Metric], ± 10%, X5R, AVX 0603 MLCC"
			(at 0 0 0)
			(layer "F.Fab")
			(hide yes)
			(effects
				(font
					(size 1.27 1.27)
					(thickness 0.15)
				)
			)
		)
		(property "Author" "Antmicro"
			(at 0 0 0)
			(layer "B.Fab")
			(hide yes)
			(effects
				(font
					(size 1 1)
					(thickness 0.15)
				)
				(justify mirror)
			)
		)
		(property "Dielectric" ""
			(at 0 0 0)
			(layer "B.Fab")
			(hide yes)
			(effects
				(font
					(size 1 1)
					(thickness 0.15)
				)
				(justify mirror)
			)
		)
		(property "License" "Apache-2.0"
			(at 0 0 0)
			(layer "B.Fab")
			(hide yes)
			(effects
				(font
					(size 1 1)
					(thickness 0.15)
				)
				(justify mirror)
			)
		)
		(property "MPN" "0603YD105KAT2A"
			(at 0 0 0)
			(layer "B.Fab")
			(hide yes)
			(effects
				(font
					(size 1 1)
					(thickness 0.15)
				)
				(justify mirror)
			)
		)
		(property "Manufacturer" "KYOCERA AVX"
			(at 0 0 0)
			(layer "B.Fab")
			(hide yes)
			(effects
				(font
					(size 1 1)
					(thickness 0.15)
				)
				(justify mirror)
			)
		)
		(property "Public" "False"
			(at 0 0 0)
			(layer "B.Fab")
			(hide yes)
			(effects
				(font
					(size 1 1)
					(thickness 0.15)
				)
				(justify mirror)
			)
		)
		(property "Val" "1u"
			(at 0 0 0)
			(layer "B.Fab")
			(hide yes)
			(effects
				(font
					(size 1 1)
					(thickness 0.15)
				)
				(justify mirror)
			)
		)
		(property "Voltage" ""
			(at 0 0 0)
			(layer "B.Fab")
			(hide yes)
			(effects
				(font
					(size 1 1)
					(thickness 0.15)
				)
				(justify mirror)
			)
		)
		(sheetname "/")
		(sheetfile "m2-pcie-adapter.kicad_sch")
		(attr smd)
		(fp_line
			(start -0.15 -0.4)
			(end 0.15 -0.4)
			(stroke
				(width 0.15)
				(type solid)
			)
			(layer "B.SilkS")
		)
		(fp_line
			(start -0.15 0.4)
			(end 0.15 0.4)
			(stroke
				(width 0.15)
				(type solid)
			)
			(layer "B.SilkS")
		)
		(fp_rect
			(start -1.25 0.65)
			(end 1.25 -0.65)
			(stroke
				(width 0.05)
				(type solid)
			)
			(fill no)
			(layer "B.CrtYd")
		)
		(fp_rect
			(start -0.8 0.4)
			(end 0.8 -0.4)
			(stroke
				(width 0.15)
				(type solid)
			)
			(fill no)
			(layer "B.Fab")
		)
		(pad "1" smd roundrect
			(at -0.7 0)
			(size 0.8 1)
			(layers "B.Cu" "B.Mask" "B.Paste")
			(roundrect_rratio 0.2)
			(net 31 "/+3V3")
			(pintype "passive")
		)
		(pad "2" smd roundrect
			(at 0.7 0)
			(size 0.8 1)
			(layers "B.Cu" "B.Mask" "B.Paste")
			(roundrect_rratio 0.2)
			(net 60 "GND")
			(pintype "passive")
		)
	)
	(footprint "antmicro-footprints:C_0603_1608Metric"
		(layer "B.Cu")
		(at 139.890059 112.497277)
		(descr "Capacitor SMD 0603")
		(tags "capacitor 0603")
		(property "Reference" "C9"
			(at -0.05 -0.99 0)
			(layer "B.SilkS")
			(effects
				(font
					(size 0.7 0.7)
					(thickness 0.15)
				)
				(justify mirror)
			)
		)
		(property "Value" "C_1u_0603"
			(at 0 -1.9 0)
			(layer "B.Fab")
			(effects
				(font
					(size 1 1)
					(thickness 0.15)
				)
				(justify mirror)
			)
		)
		(property "Datasheet" "https://spicat.kyocera-avx.com/product/mlcc/chartview/0603YD105KAT2A/"
			(at 0 0 0)
			(layer "F.Fab")
			(hide yes)
			(effects
				(font
					(size 1.27 1.27)
					(thickness 0.15)
				)
			)
		)
		(property "Description" "SMD Multilayer Ceramic Capacitor, 1 µF, 16 V, 0603 [1608 Metric], ± 10%, X5R, AVX 0603 MLCC"
			(at 0 0 0)
			(layer "F.Fab")
			(hide yes)
			(effects
				(font
					(size 1.27 1.27)
					(thickness 0.15)
				)
			)
		)
		(property "Author" "Antmicro"
			(at 0 0 0)
			(layer "B.Fab")
			(hide yes)
			(effects
				(font
					(size 1 1)
					(thickness 0.15)
				)
				(justify mirror)
			)
		)
		(property "Dielectric" ""
			(at 0 0 0)
			(layer "B.Fab")
			(hide yes)
			(effects
				(font
					(size 1 1)
					(thickness 0.15)
				)
				(justify mirror)
			)
		)
		(property "License" "Apache-2.0"
			(at 0 0 0)
			(layer "B.Fab")
			(hide yes)
			(effects
				(font
					(size 1 1)
					(thickness 0.15)
				)
				(justify mirror)
			)
		)
		(property "MPN" "0603YD105KAT2A"
			(at 0 0 0)
			(layer "B.Fab")
			(hide yes)
			(effects
				(font
					(size 1 1)
					(thickness 0.15)
				)
				(justify mirror)
			)
		)
		(property "Manufacturer" "KYOCERA AVX"
			(at 0 0 0)
			(layer "B.Fab")
			(hide yes)
			(effects
				(font
					(size 1 1)
					(thickness 0.15)
				)
				(justify mirror)
			)
		)
		(property "Public" "False"
			(at 0 0 0)
			(layer "B.Fab")
			(hide yes)
			(effects
				(font
					(size 1 1)
					(thickness 0.15)
				)
				(justify mirror)
			)
		)
		(property "Val" "1u"
			(at 0 0 0)
			(layer "B.Fab")
			(hide yes)
			(effects
				(font
					(size 1 1)
					(thickness 0.15)
				)
				(justify mirror)
			)
		)
		(property "Voltage" ""
			(at 0 0 0)
			(layer "B.Fab")
			(hide yes)
			(effects
				(font
					(size 1 1)
					(thickness 0.15)
				)
				(justify mirror)
			)
		)
		(sheetname "/")
		(sheetfile "m2-pcie-adapter.kicad_sch")
		(attr smd)
		(fp_line
			(start -0.15 -0.4)
			(end 0.15 -0.4)
			(stroke
				(width 0.15)
				(type solid)
			)
			(layer "B.SilkS")
		)
		(fp_line
			(start -0.15 0.4)
			(end 0.15 0.4)
			(stroke
				(width 0.15)
				(type solid)
			)
			(layer "B.SilkS")
		)
		(fp_rect
			(start -1.25 0.65)
			(end 1.25 -0.65)
			(stroke
				(width 0.05)
				(type solid)
			)
			(fill no)
			(layer "B.CrtYd")
		)
		(fp_rect
			(start -0.8 0.4)
			(end 0.8 -0.4)
			(stroke
				(width 0.15)
				(type solid)
			)
			(fill no)
			(layer "B.Fab")
		)
		(pad "1" smd roundrect
			(at -0.7 0)
			(size 0.8 1)
			(layers "B.Cu" "B.Mask" "B.Paste")
			(roundrect_rratio 0.2)
			(net 31 "/+3V3")
			(pintype "passive")
		)
		(pad "2" smd roundrect
			(at 0.7 0)
			(size 0.8 1)
			(layers "B.Cu" "B.Mask" "B.Paste")
			(roundrect_rratio 0.2)
			(net 60 "GND")
			(pintype "passive")
		)
	)
	(footprint "antmicro-footprints:C_0402_1005Metric"
		(layer "B.Cu")
		(at 137.530059 112.367277 180)
		(descr "Capacitor SMD 0402")
		(tags "capacitor SMD 0402")
		(property "Reference" "C5"
			(at 1.47 -0.06 0)
			(layer "B.SilkS")
			(effects
				(font
					(size 0.7 0.7)
					(thickness 0.15)
				)
				(justify mirror)
			)
		)
		(property "Value" "C_100n_16V_X7R_0402"
			(at 0 -1.17 0)
			(layer "B.Fab")
			(effects
				(font
					(size 1 1)
					(thickness 0.15)
				)
				(justify mirror)
			)
		)
		(property "Datasheet" "https://www.kemet.com/en/us/capacitors/product/C0402C104J4RAC7411.html"
			(at 0 0 180)
			(layer "F.Fab")
			(hide yes)
			(effects
				(font
					(size 1.27 1.27)
					(thickness 0.15)
				)
			)
		)
		(property "Description" "SMD Multilayer Ceramic Capacitor, 100nF, 50V, 0402, ±5%, X7R"
			(at 0 0 180)
			(layer "F.Fab")
			(hide yes)
			(effects
				(font
					(size 1.27 1.27)
					(thickness 0.15)
				)
			)
		)
		(property "Author" "Antmicro"
			(at 275.060118 224.734554 0)
			(layer "B.Fab")
			(hide yes)
			(effects
				(font
					(size 1 1)
					(thickness 0.15)
				)
				(justify mirror)
			)
		)
		(property "Dielectric" "X7R"
			(at 275.060118 224.734554 0)
			(layer "B.Fab")
			(hide yes)
			(effects
				(font
					(size 1 1)
					(thickness 0.15)
				)
				(justify mirror)
			)
		)
		(property "License" "Apache-2.0"
			(at 275.060118 224.734554 0)
			(layer "B.Fab")
			(hide yes)
			(effects
				(font
					(size 1 1)
					(thickness 0.15)
				)
				(justify mirror)
			)
		)
		(property "MPN" "C0402C104J4RAC7411"
			(at 275.060118 224.734554 0)
			(layer "B.Fab")
			(hide yes)
			(effects
				(font
					(size 1 1)
					(thickness 0.15)
				)
				(justify mirror)
			)
		)
		(property "Manufacturer" "KEMET"
			(at 275.060118 224.734554 0)
			(layer "B.Fab")
			(hide yes)
			(effects
				(font
					(size 1 1)
					(thickness 0.15)
				)
				(justify mirror)
			)
		)
		(property "Val" "100n"
			(at 275.060118 224.734554 0)
			(layer "B.Fab")
			(hide yes)
			(effects
				(font
					(size 1 1)
					(thickness 0.15)
				)
				(justify mirror)
			)
		)
		(property "Voltage" "16V"
			(at 275.060118 224.734554 0)
			(layer "B.Fab")
			(hide yes)
			(effects
				(font
					(size 1 1)
					(thickness 0.15)
				)
				(justify mirror)
			)
		)
		(sheetname "/")
		(sheetfile "m2-pcie-adapter.kicad_sch")
		(attr smd)
		(fp_rect
			(start -0.925 0.47)
			(end 0.925 -0.47)
			(stroke
				(width 0.05)
				(type default)
			)
			(fill no)
			(layer "B.CrtYd")
		)
		(fp_line
			(start 0.504 0.25)
			(end 0.504 -0.248)
			(stroke
				(width 0.15)
				(type solid)
			)
			(layer "B.Fab")
		)
		(fp_line
			(start 0.504 -0.248)
			(end -0.494 -0.248)
			(stroke
				(width 0.15)
				(type solid)
			)
			(layer "B.Fab")
		)
		(fp_line
			(start -0.494 0.25)
			(end 0.504 0.25)
			(stroke
				(width 0.15)
				(type solid)
			)
			(layer "B.Fab")
		)
		(fp_line
			(start -0.494 -0.248)
			(end -0.494 0.25)
			(stroke
				(width 0.15)
				(type solid)
			)
			(layer "B.Fab")
		)
		(fp_text user "${REFERENCE}"
			(at 0 0 0)
			(layer "B.Fab")
			(effects
				(font
					(size 0.25 0.25)
					(thickness 0.04)
				)
				(justify mirror)
			)
		)
		(pad "1" smd roundrect
			(at -0.48 0 180)
			(size 0.59 0.64)
			(layers "B.Cu" "B.Mask" "B.Paste")
			(roundrect_rratio 0.25)
			(net 62 "/+3V3_AUX")
			(pintype "passive")
		)
		(pad "2" smd roundrect
			(at 0.48 0 180)
			(size 0.59 0.64)
			(layers "B.Cu" "B.Mask" "B.Paste")
			(roundrect_rratio 0.25)
			(net 60 "GND")
			(pintype "passive")
		)
	)
	(footprint "antmicro-footprints:R_0402_1005Metric"
		(layer "B.Cu")
		(at 135.680059 109.087277 90)
		(descr "Resistor SMD 0402")
		(tags "resistor SMD 0402")
		(property "Reference" "R4"
			(at -1.52 0.01 270)
			(layer "B.SilkS")
			(effects
				(font
					(size 0.7 0.7)
					(thickness 0.15)
				)
				(justify mirror)
			)
		)
		(property "Value" "R_0R_0402"
			(at 0 -1.17 90)
			(layer "B.Fab")
			(effects
				(font
					(size 1 1)
					(thickness 0.15)
				)
				(justify mirror)
			)
		)
		(property "Datasheet" "https://industrial.panasonic.com/cdbs/www-data/pdf/RDA0000/AOA0000C301.pdf"
			(at 0 0 90)
			(layer "F.Fab")
			(hide yes)
			(effects
				(font
					(size 1.27 1.27)
					(thickness 0.15)
				)
			)
		)
		(property "Description" "SMD Chip Resistor, Jumper, 0 ohm, 100 mW, 0402 [1005 Metric], Thick Film, General Purpose"
			(at 0 0 90)
			(layer "F.Fab")
			(hide yes)
			(effects
				(font
					(size 1.27 1.27)
					(thickness 0.15)
				)
			)
		)
		(property "Author" "Antmicro"
			(at 244.767336 -26.592782 0)
			(layer "B.Fab")
			(hide yes)
			(effects
				(font
					(size 1 1)
					(thickness 0.15)
				)
				(justify mirror)
			)
		)
		(property "Current" "1A"
			(at 244.767336 -26.592782 0)
			(layer "B.Fab")
			(hide yes)
			(effects
				(font
					(size 1 1)
					(thickness 0.15)
				)
				(justify mirror)
			)
		)
		(property "License" "Apache-2.0"
			(at 244.767336 -26.592782 0)
			(layer "B.Fab")
			(hide yes)
			(effects
				(font
					(size 1 1)
					(thickness 0.15)
				)
				(justify mirror)
			)
		)
		(property "MPN" "ERJ2GE0R00X"
			(at 244.767336 -26.592782 0)
			(layer "B.Fab")
			(hide yes)
			(effects
				(font
					(size 1 1)
					(thickness 0.15)
				)
				(justify mirror)
			)
		)
		(property "Manufacturer" "Panasonic"
			(at 244.767336 -26.592782 0)
			(layer "B.Fab")
			(hide yes)
			(effects
				(font
					(size 1 1)
					(thickness 0.15)
				)
				(justify mirror)
			)
		)
		(property "Public" "False"
			(at 244.767336 -26.592782 0)
			(layer "B.Fab")
			(hide yes)
			(effects
				(font
					(size 1 1)
					(thickness 0.15)
				)
				(justify mirror)
			)
		)
		(property "Tolerance" ""
			(at 244.767336 -26.592782 0)
			(layer "B.Fab")
			(hide yes)
			(effects
				(font
					(size 1 1)
					(thickness 0.15)
				)
				(justify mirror)
			)
		)
		(property "Val" "0R"
			(at 244.767336 -26.592782 0)
			(layer "B.Fab")
			(hide yes)
			(effects
				(font
					(size 1 1)
					(thickness 0.15)
				)
				(justify mirror)
			)
		)
		(sheetname "/")
		(sheetfile "m2-pcie-adapter.kicad_sch")
		(attr smd)
		(fp_rect
			(start -0.925 0.47)
			(end 0.925 -0.47)
			(stroke
				(width 0.05)
				(type default)
			)
			(fill no)
			(layer "B.CrtYd")
		)
		(fp_rect
			(start -0.5 0.25)
			(end 0.5 -0.25)
			(stroke
				(width 0.15)
				(type solid)
			)
			(fill no)
			(layer "B.Fab")
		)
		(fp_text user "${REFERENCE}"
			(at 0 0 90)
			(layer "B.Fab")
			(effects
				(font
					(size 0.25 0.25)
					(thickness 0.04)
				)
				(justify mirror)
			)
		)
		(pad "1" smd roundrect
			(at -0.48 0 90)
			(size 0.59 0.64)
			(layers "B.Cu" "B.Mask" "B.Paste")
			(roundrect_rratio 0.25)
			(net 11 "Net-(J1-PWRGD)")
			(pintype "passive")
		)
		(pad "2" smd roundrect
			(at 0.48 0 90)
			(size 0.59 0.64)
			(layers "B.Cu" "B.Mask" "B.Paste")
			(roundrect_rratio 0.25)
			(net 59 "/PWRGD")
			(pintype "passive")
		)
	)
	(footprint "antmicro-footprints:R_0402_1005Metric"
		(layer "B.Cu")
		(at 137.200059 109.037277 -90)
		(descr "Resistor SMD 0402")
		(tags "resistor SMD 0402")
		(property "Reference" "R3"
			(at 1.58 -0.04 90)
			(layer "B.SilkS")
			(effects
				(font
					(size 0.7 0.7)
					(thickness 0.15)
				)
				(justify mirror)
			)
		)
		(property "Value" "R_0R_0402"
			(at 0 -1.17 90)
			(layer "B.Fab")
			(effects
				(font
					(size 1 1)
					(thickness 0.15)
				)
				(justify mirror)
			)
		)
		(property "Datasheet" "https://industrial.panasonic.com/cdbs/www-data/pdf/RDA0000/AOA0000C301.pdf"
			(at 0 0 270)
			(layer "F.Fab")
			(hide yes)
			(effects
				(font
					(size 1.27 1.27)
					(thickness 0.15)
				)
			)
		)
		(property "Description" "SMD Chip Resistor, Jumper, 0 ohm, 100 mW, 0402 [1005 Metric], Thick Film, General Purpose"
			(at 0 0 270)
			(layer "F.Fab")
			(hide yes)
			(effects
				(font
					(size 1.27 1.27)
					(thickness 0.15)
				)
			)
		)
		(property "Author" "Antmicro"
			(at 28.162782 246.237336 0)
			(layer "B.Fab")
			(hide yes)
			(effects
				(font
					(size 1 1)
					(thickness 0.15)
				)
				(justify mirror)
			)
		)
		(property "Current" "1A"
			(at 28.162782 246.237336 0)
			(layer "B.Fab")
			(hide yes)
			(effects
				(font
					(size 1 1)
					(thickness 0.15)
				)
				(justify mirror)
			)
		)
		(property "License" "Apache-2.0"
			(at 28.162782 246.237336 0)
			(layer "B.Fab")
			(hide yes)
			(effects
				(font
					(size 1 1)
					(thickness 0.15)
				)
				(justify mirror)
			)
		)
		(property "MPN" "ERJ2GE0R00X"
			(at 28.162782 246.237336 0)
			(layer "B.Fab")
			(hide yes)
			(effects
				(font
					(size 1 1)
					(thickness 0.15)
				)
				(justify mirror)
			)
		)
		(property "Manufacturer" "Panasonic"
			(at 28.162782 246.237336 0)
			(layer "B.Fab")
			(hide yes)
			(effects
				(font
					(size 1 1)
					(thickness 0.15)
				)
				(justify mirror)
			)
		)
		(property "Public" "False"
			(at 28.162782 246.237336 0)
			(layer "B.Fab")
			(hide yes)
			(effects
				(font
					(size 1 1)
					(thickness 0.15)
				)
				(justify mirror)
			)
		)
		(property "Tolerance" ""
			(at 28.162782 246.237336 0)
			(layer "B.Fab")
			(hide yes)
			(effects
				(font
					(size 1 1)
					(thickness 0.15)
				)
				(justify mirror)
			)
		)
		(property "Val" "0R"
			(at 28.162782 246.237336 0)
			(layer "B.Fab")
			(hide yes)
			(effects
				(font
					(size 1 1)
					(thickness 0.15)
				)
				(justify mirror)
			)
		)
		(sheetname "/")
		(sheetfile "m2-pcie-adapter.kicad_sch")
		(attr smd)
		(fp_rect
			(start -0.925 0.47)
			(end 0.925 -0.47)
			(stroke
				(width 0.05)
				(type default)
			)
			(fill no)
			(layer "B.CrtYd")
		)
		(fp_rect
			(start -0.5 0.25)
			(end 0.5 -0.25)
			(stroke
				(width 0.15)
				(type solid)
			)
			(fill no)
			(layer "B.Fab")
		)
		(fp_text user "${REFERENCE}"
			(at 0 0 90)
			(layer "B.Fab")
			(effects
				(font
					(size 0.25 0.25)
					(thickness 0.04)
				)
				(justify mirror)
			)
		)
		(pad "1" smd roundrect
			(at -0.48 0 270)
			(size 0.59 0.64)
			(layers "B.Cu" "B.Mask" "B.Paste")
			(roundrect_rratio 0.25)
			(net 63 "/WAKE#")
			(pintype "passive")
		)
		(pad "2" smd roundrect
			(at 0.48 0 270)
			(size 0.59 0.64)
			(layers "B.Cu" "B.Mask" "B.Paste")
			(roundrect_rratio 0.25)
			(net 5 "Net-(J1-WAKE#)")
			(pintype "passive")
		)
	)
	(footprint "antmicro-footprints:oshw-logo"
		(layer "B.Cu")
		(at 159.170059 92.357277 180)
		(descr "OSHW Logo")
		(tags "OSHW Logo")
		(property "Reference" "N2"
			(at -3.08 4.76 0)
			(layer "B.SilkS")
			(hide yes)
			(effects
				(font
					(size 0.7 0.7)
					(thickness 0.15)
				)
				(justify mirror)
			)
		)
		(property "Value" "oshw_logo"
			(at 3.43 4.88 0)
			(layer "B.Fab")
			(hide yes)
			(effects
				(font
					(size 0.7 0.7)
					(thickness 0.15)
				)
				(justify mirror)
			)
		)
		(property "Description" "Mechanical part"
			(at 0 0 180)
			(layer "F.Fab")
			(hide yes)
			(effects
				(font
					(size 1.27 1.27)
					(thickness 0.15)
				)
			)
		)
		(property "Author" "Antmicro"
			(at 318.340118 184.714554 0)
			(layer "B.Fab")
			(hide yes)
			(effects
				(font
					(size 1 1)
					(thickness 0.15)
				)
				(justify mirror)
			)
		)
		(property "License" "Apache-2.0"
			(at 318.340118 184.714554 0)
			(layer "B.Fab")
			(hide yes)
			(effects
				(font
					(size 1 1)
					(thickness 0.15)
				)
				(justify mirror)
			)
		)
		(property "MPN" ""
			(at 318.340118 184.714554 0)
			(layer "B.Fab")
			(hide yes)
			(effects
				(font
					(size 1 1)
					(thickness 0.15)
				)
				(justify mirror)
			)
		)
		(property "Manufacturer" ""
			(at 318.340118 184.714554 0)
			(layer "B.Fab")
			(hide yes)
			(effects
				(font
					(size 1 1)
					(thickness 0.15)
				)
				(justify mirror)
			)
		)
		(property "Public" "False"
			(at 318.340118 184.714554 0)
			(layer "B.Fab")
			(hide yes)
			(effects
				(font
					(size 1 1)
					(thickness 0.15)
				)
				(justify mirror)
			)
		)
		(sheetname "/")
		(sheetfile "m2-pcie-adapter.kicad_sch")
		(attr exclude_from_pos_files allow_soldermask_bridges)
		(fp_poly
			(pts
				(xy -0.843 -2.558) (xy -0.815 -2.564) (xy -0.794 -2.572) (xy -0.773 -2.581) (xy -0.759 -2.589) (xy -0.738 -2.603)
				(xy -0.783 -2.658) (xy -0.8 -2.677) (xy -0.814 -2.694) (xy -0.825 -2.706) (xy -0.831 -2.712) (xy -0.832 -2.712)
				(xy -0.837 -2.71) (xy -0.847 -2.703) (xy -0.849 -2.702) (xy -0.874 -2.69) (xy -0.904 -2.684) (xy -0.935 -2.685)
				(xy -0.942 -2.686) (xy -0.975 -2.698) (xy -1.001 -2.717) (xy -1.02 -2.741) (xy -1.034 -2.766) (xy -1.039 -3.197)
				(xy -1.164 -3.2) (xy -1.164 -2.565) (xy -1.037 -2.565) (xy -1.037 -2.626) (xy -1.009 -2.604) (xy -0.972 -2.579)
				(xy -0.931 -2.563) (xy -0.887 -2.556) (xy -0.843 -2.558)
			)
			(stroke
				(width 0.01)
				(type solid)
			)
			(fill yes)
			(layer "B.Cu")
		)
		(fp_poly
			(pts
				(xy 1.889 -1.554) (xy 1.907 -1.559) (xy 1.927 -1.566) (xy 1.948 -1.574) (xy 1.966 -1.583) (xy 1.979 -1.592)
				(xy 1.984 -1.597) (xy 1.982 -1.604) (xy 1.974 -1.616) (xy 1.962 -1.633) (xy 1.946 -1.652) (xy 1.945 -1.654)
				(xy 1.929 -1.673) (xy 1.915 -1.689) (xy 1.906 -1.7) (xy 1.901 -1.706) (xy 1.896 -1.705) (xy 1.885 -1.7)
				(xy 1.873 -1.695) (xy 1.84 -1.683) (xy 1.808 -1.68) (xy 1.776 -1.685) (xy 1.747 -1.698) (xy 1.723 -1.717)
				(xy 1.704 -1.742) (xy 1.696 -1.763) (xy 1.695 -1.772) (xy 1.694 -1.79) (xy 1.693 -1.817) (xy 1.692 -1.85)
				(xy 1.692 -1.89) (xy 1.691 -1.934) (xy 1.691 -1.983) (xy 1.691 -2.194) (xy 1.559 -2.194) (xy 1.559 -1.559)
				(xy 1.691 -1.559) (xy 1.691 -1.626) (xy 1.71 -1.607) (xy 1.739 -1.585) (xy 1.775 -1.568) (xy 1.814 -1.556)
				(xy 1.855 -1.552) (xy 1.889 -1.554)
			)
			(stroke
				(width 0.01)
				(type solid)
			)
			(fill yes)
			(layer "B.Cu")
		)
		(fp_poly
			(pts
				(xy -0.837 -1.56) (xy -0.797 -1.576) (xy -0.761 -1.6) (xy -0.73 -1.63) (xy -0.706 -1.667) (xy -0.69 -1.709)
				(xy -0.687 -1.721) (xy -0.685 -1.734) (xy -0.684 -1.757) (xy -0.683 -1.79) (xy -0.682 -1.833) (xy -0.681 -1.884)
				(xy -0.681 -1.945) (xy -0.681 -1.971) (xy -0.681 -2.194) (xy -0.808 -2.194) (xy -0.809 -1.984) (xy -0.811 -1.774)
				(xy -0.826 -1.744) (xy -0.845 -1.716) (xy -0.868 -1.697) (xy -0.897 -1.686) (xy -0.925 -1.682) (xy -0.947 -1.682)
				(xy -0.967 -1.684) (xy -0.979 -1.686) (xy -1.001 -1.698) (xy -1.023 -1.716) (xy -1.041 -1.738) (xy -1.049 -1.752)
				(xy -1.052 -1.758) (xy -1.054 -1.765) (xy -1.056 -1.773) (xy -1.057 -1.783) (xy -1.058 -1.797) (xy -1.059 -1.815)
				(xy -1.06 -1.839) (xy -1.06 -1.869) (xy -1.061 -1.907) (xy -1.061 -1.953) (xy -1.061 -1.985) (xy -1.063 -2.194)
				(xy -1.189 -2.194) (xy -1.189 -1.559) (xy -1.062 -1.559) (xy -1.062 -1.625) (xy -1.033 -1.602) (xy -1.001 -1.579)
				(xy -0.969 -1.564) (xy -0.934 -1.555) (xy -0.927 -1.554) (xy -0.881 -1.553) (xy -0.837 -1.56)
			)
			(stroke
				(width 0.01)
				(type solid)
			)
			(fill yes)
			(layer "B.Cu")
		)
		(fp_poly
			(pts
				(xy 1.042 -1.769) (xy 1.043 -1.979) (xy 1.059 -2.009) (xy 1.077 -2.036) (xy 1.1 -2.056) (xy 1.129 -2.067)
				(xy 1.159 -2.071) (xy 1.193 -2.07) (xy 1.221 -2.063) (xy 1.245 -2.047) (xy 1.258 -2.034) (xy 1.266 -2.025)
				(xy 1.273 -2.016) (xy 1.278 -2.008) (xy 1.282 -1.997) (xy 1.286 -1.985) (xy 1.288 -1.969) (xy 1.29 -1.948)
				(xy 1.291 -1.922) (xy 1.292 -1.89) (xy 1.293 -1.85) (xy 1.293 -1.801) (xy 1.294 -1.766) (xy 1.295 -1.559)
				(xy 1.422 -1.559) (xy 1.422 -2.194) (xy 1.295 -2.194) (xy 1.295 -2.161) (xy 1.295 -2.144) (xy 1.293 -2.132)
				(xy 1.292 -2.128) (xy 1.287 -2.131) (xy 1.278 -2.14) (xy 1.271 -2.147) (xy 1.256 -2.159) (xy 1.236 -2.171)
				(xy 1.219 -2.181) (xy 1.202 -2.188) (xy 1.186 -2.193) (xy 1.17 -2.196) (xy 1.148 -2.197) (xy 1.135 -2.198)
				(xy 1.107 -2.198) (xy 1.087 -2.197) (xy 1.07 -2.194) (xy 1.059 -2.19) (xy 1.036 -2.181) (xy 1.019 -2.172)
				(xy 1.003 -2.161) (xy 0.985 -2.146) (xy 0.981 -2.141) (xy 0.952 -2.107) (xy 0.931 -2.068) (xy 0.92 -2.033)
				(xy 0.918 -2.019) (xy 0.917 -1.996) (xy 0.916 -1.963) (xy 0.915 -1.92) (xy 0.914 -1.869) (xy 0.914 -1.808)
				(xy 0.914 -1.782) (xy 0.914 -1.559) (xy 1.04 -1.559) (xy 1.042 -1.769)
			)
			(stroke
				(width 0.01)
				(type solid)
			)
			(fill yes)
			(layer "B.Cu")
		)
		(fp_poly
			(pts
				(xy 1.753 -2.563) (xy 1.768 -2.568) (xy 1.787 -2.577) (xy 1.804 -2.586) (xy 1.818 -2.595) (xy 1.826 -2.602)
				(xy 1.827 -2.606) (xy 1.824 -2.611) (xy 1.815 -2.621) (xy 1.803 -2.636) (xy 1.789 -2.654) (xy 1.775 -2.671)
				(xy 1.761 -2.688) (xy 1.749 -2.701) (xy 1.742 -2.71) (xy 1.739 -2.712) (xy 1.735 -2.71) (xy 1.724 -2.704)
				(xy 1.713 -2.698) (xy 1.697 -2.69) (xy 1.682 -2.686) (xy 1.664 -2.685) (xy 1.653 -2.685) (xy 1.618 -2.688)
				(xy 1.59 -2.699) (xy 1.566 -2.718) (xy 1.561 -2.723) (xy 1.554 -2.732) (xy 1.548 -2.74) (xy 1.544 -2.748)
				(xy 1.54 -2.758) (xy 1.537 -2.769) (xy 1.534 -2.785) (xy 1.533 -2.804) (xy 1.532 -2.829) (xy 1.531 -2.861)
				(xy 1.53 -2.899) (xy 1.53 -2.947) (xy 1.53 -2.988) (xy 1.528 -3.2) (xy 1.468 -3.2) (xy 1.444 -3.2)
				(xy 1.425 -3.199) (xy 1.411 -3.198) (xy 1.405 -3.197) (xy 1.404 -3.191) (xy 1.404 -3.176) (xy 1.403 -3.153)
				(xy 1.403 -3.122) (xy 1.402 -3.085) (xy 1.402 -3.042) (xy 1.402 -2.993) (xy 1.402 -2.941) (xy 1.402 -2.886)
				(xy 1.402 -2.565) (xy 1.529 -2.565) (xy 1.529 -2.595) (xy 1.529 -2.611) (xy 1.53 -2.623) (xy 1.532 -2.626)
				(xy 1.537 -2.623) (xy 1.547 -2.615) (xy 1.554 -2.608) (xy 1.588 -2.584) (xy 1.627 -2.567) (xy 1.669 -2.558)
				(xy 1.712 -2.556) (xy 1.753 -2.563)
			)
			(stroke
				(width 0.01)
				(type solid)
			)
			(fill yes)
			(layer "B.Cu")
		)
		(fp_poly
			(pts
				(xy 2.316 -1.557) (xy 2.365 -1.57) (xy 2.41 -1.593) (xy 2.453 -1.625) (xy 2.46 -1.631) (xy 2.491 -1.661)
				(xy 2.466 -1.684) (xy 2.448 -1.699) (xy 2.43 -1.715) (xy 2.419 -1.725) (xy 2.397 -1.743) (xy 2.376 -1.724)
				(xy 2.345 -1.701) (xy 2.312 -1.687) (xy 2.274 -1.681) (xy 2.265 -1.681) (xy 2.226 -1.684) (xy 2.195 -1.693)
				(xy 2.167 -1.708) (xy 2.159 -1.715) (xy 2.136 -1.741) (xy 2.118 -1.776) (xy 2.107 -1.817) (xy 2.103 -1.866)
				(xy 2.103 -1.876) (xy 2.106 -1.926) (xy 2.116 -1.97) (xy 2.132 -2.006) (xy 2.155 -2.034) (xy 2.184 -2.055)
				(xy 2.219 -2.067) (xy 2.259 -2.072) (xy 2.274 -2.071) (xy 2.309 -2.066) (xy 2.339 -2.056) (xy 2.366 -2.038)
				(xy 2.377 -2.028) (xy 2.386 -2.02) (xy 2.393 -2.016) (xy 2.4 -2.015) (xy 2.409 -2.018) (xy 2.42 -2.027)
				(xy 2.436 -2.041) (xy 2.456 -2.059) (xy 2.491 -2.092) (xy 2.476 -2.108) (xy 2.449 -2.132) (xy 2.416 -2.155)
				(xy 2.38 -2.174) (xy 2.35 -2.186) (xy 2.327 -2.193) (xy 2.306 -2.197) (xy 2.283 -2.199) (xy 2.259 -2.199)
				(xy 2.233 -2.198) (xy 2.209 -2.196) (xy 2.189 -2.193) (xy 2.182 -2.191) (xy 2.133 -2.173) (xy 2.089 -2.146)
				(xy 2.053 -2.112) (xy 2.023 -2.071) (xy 2.012 -2.051) (xy 2 -2.023) (xy 1.991 -1.999) (xy 1.984 -1.975)
				(xy 1.981 -1.948) (xy 1.979 -1.917) (xy 1.978 -1.879) (xy 1.978 -1.877) (xy 1.979 -1.838) (xy 1.98 -1.806)
				(xy 1.984 -1.78) (xy 1.99 -1.756) (xy 1.999 -1.731) (xy 2.011 -1.704) (xy 2.012 -1.701) (xy 2.039 -1.657)
				(xy 2.072 -1.62) (xy 2.111 -1.591) (xy 2.156 -1.57) (xy 2.207 -1.557) (xy 2.263 -1.552) (xy 2.316 -1.557)
			)
			(stroke
				(width 0.01)
				(type solid)
			)
			(fill yes)
			(layer "B.Cu")
		)
		(fp_poly
			(pts
				(xy -1.494 -1.56) (xy -1.447 -1.576) (xy -1.405 -1.6) (xy -1.368 -1.633) (xy -1.341 -1.668) (xy -1.326 -1.692)
				(xy -1.316 -1.716) (xy -1.308 -1.743) (xy -1.302 -1.774) (xy -1.299 -1.811) (xy -1.297 -1.845) (xy -1.294 -1.925)
				(xy -1.692 -1.925) (xy -1.692 -1.942) (xy -1.687 -1.977) (xy -1.673 -2.011) (xy -1.65 -2.039) (xy -1.626 -2.059)
				(xy -1.601 -2.071) (xy -1.572 -2.078) (xy -1.537 -2.079) (xy -1.497 -2.074) (xy -1.458 -2.06) (xy -1.422 -2.036)
				(xy -1.421 -2.036) (xy -1.402 -2.021) (xy -1.359 -2.057) (xy -1.342 -2.072) (xy -1.327 -2.085) (xy -1.317 -2.094)
				(xy -1.314 -2.098) (xy -1.316 -2.103) (xy -1.324 -2.113) (xy -1.338 -2.126) (xy -1.354 -2.139) (xy -1.372 -2.152)
				(xy -1.389 -2.163) (xy -1.399 -2.168) (xy -1.421 -2.178) (xy -1.445 -2.187) (xy -1.461 -2.191) (xy -1.488 -2.196)
				(xy -1.522 -2.199) (xy -1.557 -2.199) (xy -1.591 -2.196) (xy -1.62 -2.192) (xy -1.629 -2.19) (xy -1.677 -2.171)
				(xy -1.718 -2.146) (xy -1.752 -2.114) (xy -1.779 -2.074) (xy -1.8 -2.026) (xy -1.802 -2.02) (xy -1.81 -1.989)
				(xy -1.815 -1.951) (xy -1.818 -1.908) (xy -1.819 -1.865) (xy -1.818 -1.823) (xy -1.816 -1.804) (xy -1.692 -1.804)
				(xy -1.692 -1.818) (xy -1.428 -1.818) (xy -1.428 -1.801) (xy -1.432 -1.775) (xy -1.442 -1.748) (xy -1.457 -1.722)
				(xy -1.469 -1.707) (xy -1.495 -1.688) (xy -1.526 -1.676) (xy -1.56 -1.672) (xy -1.593 -1.676) (xy -1.619 -1.685)
				(xy -1.646 -1.704) (xy -1.668 -1.73) (xy -1.683 -1.76) (xy -1.691 -1.792) (xy -1.692 -1.804) (xy -1.816 -1.804)
				(xy -1.814 -1.786) (xy -1.812 -1.777) (xy -1.797 -1.724) (xy -1.775 -1.676) (xy -1.747 -1.636) (xy -1.713 -1.603)
				(xy -1.673 -1.578) (xy -1.629 -1.561) (xy -1.597 -1.554) (xy -1.544 -1.552) (xy -1.494 -1.56)
			)
			(stroke
				(width 0.01)
				(type solid)
			)
			(fill yes)
			(layer "B.Cu")
		)
		(fp_poly
			(pts
				(xy 2.835 -1.557) (xy 2.883 -1.57) (xy 2.926 -1.592) (xy 2.964 -1.621) (xy 2.996 -1.657) (xy 3.021 -1.699)
				(xy 3.038 -1.747) (xy 3.04 -1.757) (xy 3.043 -1.776) (xy 3.045 -1.802) (xy 3.047 -1.832) (xy 3.047 -1.858)
				(xy 3.047 -1.925) (xy 2.65 -1.925) (xy 2.653 -1.951) (xy 2.663 -1.991) (xy 2.68 -2.024) (xy 2.703 -2.049)
				(xy 2.733 -2.067) (xy 2.77 -2.077) (xy 2.801 -2.079) (xy 2.845 -2.075) (xy 2.883 -2.063) (xy 2.916 -2.042)
				(xy 2.92 -2.039) (xy 2.929 -2.031) (xy 2.935 -2.026) (xy 2.941 -2.025) (xy 2.949 -2.027) (xy 2.959 -2.034)
				(xy 2.974 -2.047) (xy 2.994 -2.064) (xy 3.01 -2.078) (xy 3.023 -2.088) (xy 3.03 -2.095) (xy 3.032 -2.096)
				(xy 3.03 -2.1) (xy 3.022 -2.11) (xy 3.01 -2.122) (xy 3.009 -2.123) (xy 2.98 -2.147) (xy 2.945 -2.169)
				(xy 2.906 -2.185) (xy 2.887 -2.191) (xy 2.861 -2.196) (xy 2.828 -2.198) (xy 2.793 -2.198) (xy 2.759 -2.197)
				(xy 2.729 -2.193) (xy 2.721 -2.191) (xy 2.675 -2.175) (xy 2.634 -2.15) (xy 2.599 -2.118) (xy 2.569 -2.077)
				(xy 2.547 -2.029) (xy 2.536 -1.996) (xy 2.532 -1.973) (xy 2.529 -1.942) (xy 2.527 -1.906) (xy 2.527 -1.869)
				(xy 2.528 -1.832) (xy 2.529 -1.818) (xy 2.65 -1.818) (xy 2.922 -1.818) (xy 2.918 -1.799) (xy 2.908 -1.758)
				(xy 2.891 -1.725) (xy 2.869 -1.7) (xy 2.84 -1.683) (xy 2.826 -1.678) (xy 2.788 -1.672) (xy 2.753 -1.675)
				(xy 2.722 -1.687) (xy 2.695 -1.706) (xy 2.674 -1.734) (xy 2.659 -1.768) (xy 2.654 -1.794) (xy 2.65 -1.818)
				(xy 2.529 -1.818) (xy 2.53 -1.798) (xy 2.534 -1.769) (xy 2.536 -1.76) (xy 2.554 -1.707) (xy 2.578 -1.662)
				(xy 2.609 -1.624) (xy 2.645 -1.593) (xy 2.687 -1.571) (xy 2.734 -1.557) (xy 2.783 -1.553) (xy 2.835 -1.557)
			)
			(stroke
				(width 0.01)
				(type solid)
			)
			(fill yes)
			(layer "B.Cu")
		)
		(fp_poly
			(pts
				(xy 2.148 -2.561) (xy 2.193 -2.574) (xy 2.235 -2.595) (xy 2.273 -2.623) (xy 2.304 -2.657) (xy 2.326 -2.691)
				(xy 2.338 -2.718) (xy 2.346 -2.745) (xy 2.352 -2.774) (xy 2.355 -2.808) (xy 2.357 -2.85) (xy 2.357 -2.858)
				(xy 2.357 -2.931) (xy 1.96 -2.931) (xy 1.963 -2.955) (xy 1.973 -2.993) (xy 1.991 -3.026) (xy 2.015 -3.053)
				(xy 2.039 -3.069) (xy 2.057 -3.076) (xy 2.08 -3.08) (xy 2.103 -3.082) (xy 2.144 -3.081) (xy 2.18 -3.071)
				(xy 2.214 -3.054) (xy 2.227 -3.045) (xy 2.24 -3.035) (xy 2.25 -3.029) (xy 2.253 -3.027) (xy 2.258 -3.03)
				(xy 2.269 -3.039) (xy 2.284 -3.05) (xy 2.3 -3.064) (xy 2.315 -3.078) (xy 2.329 -3.09) (xy 2.338 -3.099)
				(xy 2.341 -3.103) (xy 2.337 -3.11) (xy 2.327 -3.121) (xy 2.312 -3.134) (xy 2.294 -3.148) (xy 2.276 -3.161)
				(xy 2.259 -3.171) (xy 2.252 -3.175) (xy 2.204 -3.192) (xy 2.152 -3.202) (xy 2.098 -3.204) (xy 2.046 -3.198)
				(xy 2.032 -3.195) (xy 1.984 -3.178) (xy 1.943 -3.154) (xy 1.909 -3.123) (xy 1.881 -3.084) (xy 1.859 -3.037)
				(xy 1.847 -3.003) (xy 1.841 -2.972) (xy 1.838 -2.934) (xy 1.836 -2.893) (xy 1.837 -2.851) (xy 1.839 -2.824)
				(xy 1.96 -2.824) (xy 2.23 -2.824) (xy 2.23 -2.813) (xy 2.225 -2.783) (xy 2.214 -2.753) (xy 2.196 -2.725)
				(xy 2.175 -2.702) (xy 2.151 -2.686) (xy 2.128 -2.68) (xy 2.101 -2.677) (xy 2.072 -2.678) (xy 2.051 -2.683)
				(xy 2.023 -2.696) (xy 2 -2.717) (xy 1.981 -2.746) (xy 1.968 -2.779) (xy 1.963 -2.8) (xy 1.96 -2.824)
				(xy 1.839 -2.824) (xy 1.839 -2.811) (xy 1.844 -2.776) (xy 1.848 -2.76) (xy 1.866 -2.708) (xy 1.889 -2.663)
				(xy 1.919 -2.627) (xy 1.954 -2.598) (xy 1.996 -2.575) (xy 2.007 -2.571) (xy 2.054 -2.559) (xy 2.101 -2.556)
				(xy 2.148 -2.561)
			)
			(stroke
				(width 0.01)
				(type solid)
			)
			(fill yes)
			(layer "B.Cu")
		)
		(fp_poly
			(pts
				(xy -2.733 -1.557) (xy -2.685 -1.57) (xy -2.642 -1.592) (xy -2.604 -1.622) (xy -2.581 -1.649) (xy -2.562 -1.676)
				(xy -2.548 -1.706) (xy -2.537 -1.739) (xy -2.53 -1.777) (xy -2.527 -1.821) (xy -2.526 -1.873) (xy -2.527 -1.907)
				(xy -2.529 -1.956) (xy -2.534 -1.997) (xy -2.542 -2.031) (xy -2.553 -2.06) (xy -2.567 -2.086) (xy -2.587 -2.111)
				(xy -2.603 -2.129) (xy -2.637 -2.158) (xy -2.673 -2.178) (xy -2.714 -2.192) (xy -2.76 -2.198) (xy -2.789 -2.199)
				(xy -2.813 -2.198) (xy -2.835 -2.196) (xy -2.852 -2.194) (xy -2.857 -2.194) (xy -2.898 -2.179) (xy -2.937 -2.155)
				(xy -2.97 -2.126) (xy -2.993 -2.101) (xy -3.011 -2.077) (xy -3.024 -2.051) (xy -3.034 -2.022) (xy -3.041 -1.988)
				(xy -3.045 -1.947) (xy -3.047 -1.91) (xy -3.047 -1.882) (xy -2.919 -1.882) (xy -2.919 -1.968) (xy -2.903 -2.001)
				(xy -2.885 -2.031) (xy -2.863 -2.051) (xy -2.837 -2.064) (xy -2.804 -2.07) (xy -2.779 -2.07) (xy -2.755 -2.069)
				(xy -2.737 -2.065) (xy -2.722 -2.058) (xy -2.717 -2.055) (xy -2.697 -2.041) (xy -2.681 -2.025) (xy -2.67 -2.004)
				(xy -2.662 -1.978) (xy -2.657 -1.945) (xy -2.654 -1.903) (xy -2.654 -1.899) (xy -2.653 -1.848) (xy -2.656 -1.806)
				(xy -2.662 -1.772) (xy -2.673 -1.744) (xy -2.687 -1.722) (xy -2.707 -1.705) (xy -2.723 -1.695) (xy -2.755 -1.684)
				(xy -2.788 -1.68) (xy -2.821 -1.684) (xy -2.851 -1.695) (xy -2.877 -1.713) (xy -2.892 -1.729) (xy -2.901 -1.745)
				(xy -2.908 -1.76) (xy -2.913 -1.778) (xy -2.916 -1.8) (xy -2.918 -1.828) (xy -2.919 -1.864) (xy -2.919 -1.882)
				(xy -3.047 -1.882) (xy -3.048 -1.844) (xy -3.043 -1.786) (xy -3.034 -1.736) (xy -3.021 -1.695) (xy -3.004 -1.664)
				(xy -2.972 -1.624) (xy -2.935 -1.594) (xy -2.893 -1.571) (xy -2.846 -1.558) (xy -2.794 -1.553) (xy -2.787 -1.553)
				(xy -2.733 -1.557)
			)
			(stroke
				(width 0.01)
				(type solid)
			)
			(fill yes)
			(layer "B.Cu")
		)
		(fp_poly
			(pts
				(xy -0.229 -3.2) (xy -0.354 -3.197) (xy -0.355 -3.165) (xy -0.357 -3.133) (xy -0.374 -3.148) (xy -0.411 -3.175)
				(xy -0.453 -3.193) (xy -0.497 -3.203) (xy -0.542 -3.204) (xy -0.585 -3.195) (xy -0.586 -3.195) (xy -0.621 -3.181)
				(xy -0.651 -3.16) (xy -0.673 -3.141) (xy -0.689 -3.123) (xy -0.702 -3.106) (xy -0.712 -3.086) (xy -0.72 -3.064)
				(xy -0.726 -3.038) (xy -0.73 -3.007) (xy -0.732 -2.968) (xy -0.733 -2.922) (xy -0.733 -2.88) (xy -0.602 -2.88)
				(xy -0.602 -2.915) (xy -0.602 -2.942) (xy -0.601 -2.962) (xy -0.6 -2.977) (xy -0.598 -2.988) (xy -0.596 -2.998)
				(xy -0.592 -3.007) (xy -0.591 -3.01) (xy -0.574 -3.039) (xy -0.552 -3.059) (xy -0.525 -3.071) (xy -0.492 -3.076)
				(xy -0.472 -3.076) (xy -0.442 -3.072) (xy -0.418 -3.063) (xy -0.398 -3.048) (xy -0.382 -3.029) (xy -0.371 -3.004)
				(xy -0.363 -2.972) (xy -0.358 -2.933) (xy -0.356 -2.885) (xy -0.356 -2.88) (xy -0.358 -2.828) (xy -0.363 -2.785)
				(xy -0.373 -2.75) (xy -0.387 -2.724) (xy -0.406 -2.704) (xy -0.43 -2.692) (xy -0.46 -2.686) (xy -0.483 -2.685)
				(xy -0.517 -2.687) (xy -0.544 -2.696) (xy -0.565 -2.711) (xy -0.583 -2.734) (xy -0.591 -2.751) (xy -0.595 -2.76)
				(xy -0.598 -2.769) (xy -0.6 -2.779) (xy -0.601 -2.793) (xy -0.602 -2.811) (xy -0.602 -2.836) (xy -0.602 -2.869)
				(xy -0.602 -2.88) (xy -0.733 -2.88) (xy -0.733 -2.827) (xy -0.732 -2.783) (xy -0.729 -2.746) (xy -0.725 -2.716)
				(xy -0.719 -2.691) (xy -0.71 -2.67) (xy -0.699 -2.651) (xy -0.685 -2.633) (xy -0.668 -2.616) (xy -0.668 -2.615)
				(xy -0.632 -2.587) (xy -0.592 -2.567) (xy -0.55 -2.557) (xy -0.506 -2.556) (xy -0.463 -2.564) (xy -0.421 -2.582)
				(xy -0.411 -2.587) (xy -0.394 -2.598) (xy -0.377 -2.61) (xy -0.373 -2.614) (xy -0.356 -2.627) (xy -0.356 -2.306)
				(xy -0.229 -2.306) (xy -0.229 -3.2)
			)
			(stroke
				(width 0.01)
				(type solid)
			)
			(fill yes)
			(layer "B.Cu")
		)
		(fp_poly
			(pts
				(xy 0.605 -1.558) (xy 0.651 -1.574) (xy 0.694 -1.598) (xy 0.728 -1.627) (xy 0.75 -1.652) (xy 0.768 -1.678)
				(xy 0.781 -1.707) (xy 0.791 -1.739) (xy 0.797 -1.777) (xy 0.801 -1.822) (xy 0.802 -1.876) (xy 0.802 -1.877)
				(xy 0.801 -1.929) (xy 0.798 -1.973) (xy 0.792 -2.009) (xy 0.784 -2.04) (xy 0.774 -2.062) (xy 0.748 -2.103)
				(xy 0.715 -2.139) (xy 0.675 -2.167) (xy 0.632 -2.187) (xy 0.626 -2.189) (xy 0.599 -2.195) (xy 0.567 -2.198)
				(xy 0.532 -2.199) (xy 0.499 -2.197) (xy 0.471 -2.193) (xy 0.466 -2.192) (xy 0.428 -2.177) (xy 0.391 -2.155)
				(xy 0.359 -2.129) (xy 0.354 -2.123) (xy 0.332 -2.098) (xy 0.316 -2.073) (xy 0.303 -2.047) (xy 0.294 -2.017)
				(xy 0.287 -1.983) (xy 0.284 -1.943) (xy 0.282 -1.894) (xy 0.282 -1.877) (xy 0.409 -1.877) (xy 0.41 -1.918)
				(xy 0.412 -1.95) (xy 0.416 -1.976) (xy 0.423 -1.997) (xy 0.432 -2.015) (xy 0.445 -2.03) (xy 0.451 -2.037)
				(xy 0.471 -2.054) (xy 0.491 -2.064) (xy 0.514 -2.07) (xy 0.543 -2.072) (xy 0.569 -2.07) (xy 0.59 -2.065)
				(xy 0.601 -2.06) (xy 0.625 -2.047) (xy 0.642 -2.031) (xy 0.656 -2.009) (xy 0.661 -1.998) (xy 0.665 -1.989)
				(xy 0.668 -1.98) (xy 0.67 -1.969) (xy 0.671 -1.954) (xy 0.672 -1.935) (xy 0.673 -1.909) (xy 0.673 -1.877)
				(xy 0.673 -1.842) (xy 0.672 -1.817) (xy 0.671 -1.798) (xy 0.67 -1.784) (xy 0.668 -1.773) (xy 0.665 -1.764)
				(xy 0.661 -1.755) (xy 0.647 -1.73) (xy 0.632 -1.712) (xy 0.612 -1.698) (xy 0.601 -1.693) (xy 0.569 -1.683)
				(xy 0.535 -1.681) (xy 0.501 -1.686) (xy 0.471 -1.7) (xy 0.447 -1.719) (xy 0.434 -1.736) (xy 0.424 -1.753)
				(xy 0.417 -1.774) (xy 0.412 -1.8) (xy 0.41 -1.833) (xy 0.409 -1.873) (xy 0.409 -1.877) (xy 0.282 -1.877)
				(xy 0.283 -1.824) (xy 0.286 -1.78) (xy 0.292 -1.742) (xy 0.301 -1.711) (xy 0.313 -1.683) (xy 0.33 -1.657)
				(xy 0.35 -1.633) (xy 0.351 -1.632) (xy 0.385 -1.601) (xy 0.42 -1.578) (xy 0.46 -1.563) (xy 0.505 -1.554)
				(xy 0.555 -1.551) (xy 0.605 -1.558)
			)
			(stroke
				(width 0.01)
				(type solid)
			)
			(fill yes)
			(layer "B.Cu")
		)
		(fp_poly
			(pts
				(xy 0.004 -1.556) (xy 0.054 -1.566) (xy 0.102 -1.582) (xy 0.146 -1.605) (xy 0.154 -1.61) (xy 0.193 -1.636)
				(xy 0.178 -1.655) (xy 0.166 -1.668) (xy 0.152 -1.686) (xy 0.138 -1.7) (xy 0.114 -1.727) (xy 0.07 -1.705)
				(xy 0.032 -1.688) (xy -0.007 -1.677) (xy -0.044 -1.672) (xy -0.079 -1.672) (xy -0.11 -1.678) (xy -0.136 -1.69)
				(xy -0.154 -1.707) (xy -0.162 -1.724) (xy -0.164 -1.745) (xy -0.164 -1.761) (xy -0.159 -1.772) (xy -0.15 -1.782)
				(xy -0.149 -1.783) (xy -0.139 -1.791) (xy -0.128 -1.797) (xy -0.114 -1.802) (xy -0.095 -1.805) (xy -0.07 -1.808)
				(xy -0.037 -1.811) (xy -0.02 -1.813) (xy 0.027 -1.817) (xy 0.065 -1.823) (xy 0.096 -1.832) (xy 0.122 -1.842)
				(xy 0.14 -1.854) (xy 0.166 -1.879) (xy 0.186 -1.91) (xy 0.2 -1.947) (xy 0.206 -1.987) (xy 0.206 -2.018)
				(xy 0.198 -2.06) (xy 0.181 -2.097) (xy 0.155 -2.129) (xy 0.122 -2.156) (xy 0.08 -2.177) (xy 0.042 -2.189)
				(xy 0.005 -2.196) (xy -0.038 -2.199) (xy -0.083 -2.198) (xy -0.125 -2.194) (xy -0.153 -2.189) (xy -0.177 -2.181)
				(xy -0.204 -2.171) (xy -0.229 -2.16) (xy -0.232 -2.159) (xy -0.251 -2.148) (xy -0.272 -2.136) (xy -0.292 -2.122)
				(xy -0.309 -2.109) (xy -0.323 -2.098) (xy -0.33 -2.09) (xy -0.331 -2.088) (xy -0.327 -2.084) (xy -0.318 -2.073)
				(xy -0.304 -2.059) (xy -0.288 -2.043) (xy -0.246 -2) (xy -0.221 -2.021) (xy -0.184 -2.047) (xy -0.145 -2.065)
				(xy -0.102 -2.075) (xy -0.053 -2.079) (xy -0.049 -2.079) (xy -0.023 -2.079) (xy -0.004 -2.078) (xy 0.011 -2.074)
				(xy 0.025 -2.069) (xy 0.029 -2.068) (xy 0.054 -2.052) (xy 0.071 -2.033) (xy 0.079 -2.01) (xy 0.078 -1.986)
				(xy 0.074 -1.975) (xy 0.068 -1.964) (xy 0.06 -1.956) (xy 0.048 -1.949) (xy 0.031 -1.944) (xy 0.007 -1.939)
				(xy -0.024 -1.935) (xy -0.052 -1.932) (xy -0.089 -1.929) (xy -0.119 -1.925) (xy -0.142 -1.921) (xy -0.16 -1.917)
				(xy -0.176 -1.912) (xy -0.192 -1.906) (xy -0.201 -1.901) (xy -0.235 -1.879) (xy -0.262 -1.85) (xy -0.28 -1.816)
				(xy -0.29 -1.776) (xy -0.292 -1.75) (xy -0.291 -1.727) (xy -0.289 -1.705) (xy -0.286 -1.689) (xy -0.286 -1.688)
				(xy -0.273 -1.659) (xy -0.253 -1.63) (xy -0.229 -1.604) (xy -0.221 -1.599) (xy -0.185 -1.577) (xy -0.143 -1.562)
				(xy -0.096 -1.554) (xy -0.047 -1.552) (xy 0.004 -1.556)
			)
			(stroke
				(width 0.01)
				(type solid)
			)
			(fill yes)
			(layer "B.Cu")
		)
		(fp_poly
			(pts
				(xy 1.038 -2.556) (xy 1.091 -2.563) (xy 1.137 -2.576) (xy 1.177 -2.595) (xy 1.209 -2.62) (xy 1.234 -2.65)
				(xy 1.242 -2.665) (xy 1.247 -2.677) (xy 1.251 -2.691) (xy 1.255 -2.708) (xy 1.258 -2.727) (xy 1.26 -2.751)
				(xy 1.262 -2.78) (xy 1.263 -2.815) (xy 1.263 -2.858) (xy 1.264 -2.908) (xy 1.263 -2.967) (xy 1.263 -2.989)
				(xy 1.262 -3.197) (xy 1.135 -3.197) (xy 1.133 -3.171) (xy 1.132 -3.144) (xy 1.119 -3.159) (xy 1.096 -3.179)
				(xy 1.065 -3.193) (xy 1.026 -3.202) (xy 0.98 -3.204) (xy 0.976 -3.204) (xy 0.955 -3.204) (xy 0.937 -3.203)
				(xy 0.925 -3.202) (xy 0.924 -3.201) (xy 0.879 -3.189) (xy 0.839 -3.17) (xy 0.806 -3.144) (xy 0.781 -3.113)
				(xy 0.763 -3.077) (xy 0.753 -3.037) (xy 0.753 -3.005) (xy 0.873 -3.005) (xy 0.874 -3.023) (xy 0.878 -3.035)
				(xy 0.887 -3.047) (xy 0.89 -3.05) (xy 0.903 -3.063) (xy 0.917 -3.072) (xy 0.935 -3.078) (xy 0.957 -3.081)
				(xy 0.986 -3.082) (xy 1.013 -3.082) (xy 1.043 -3.081) (xy 1.065 -3.079) (xy 1.08 -3.077) (xy 1.091 -3.073)
				(xy 1.096 -3.071) (xy 1.112 -3.058) (xy 1.123 -3.039) (xy 1.13 -3.012) (xy 1.132 -2.977) (xy 1.132 -2.975)
				(xy 1.132 -2.931) (xy 1.035 -2.931) (xy 0.999 -2.931) (xy 0.973 -2.931) (xy 0.953 -2.932) (xy 0.939 -2.934)
				(xy 0.928 -2.936) (xy 0.919 -2.939) (xy 0.916 -2.94) (xy 0.893 -2.954) (xy 0.88 -2.971) (xy 0.874 -2.994)
				(xy 0.873 -3.005) (xy 0.753 -3.005) (xy 0.753 -2.994) (xy 0.761 -2.951) (xy 0.768 -2.931) (xy 0.776 -2.915)
				(xy 0.786 -2.901) (xy 0.802 -2.884) (xy 0.804 -2.882) (xy 0.82 -2.867) (xy 0.835 -2.854) (xy 0.85 -2.845)
				(xy 0.867 -2.838) (xy 0.887 -2.833) (xy 0.912 -2.829) (xy 0.943 -2.827) (xy 0.982 -2.826) (xy 1.015 -2.825)
				(xy 1.133 -2.823) (xy 1.132 -2.771) (xy 1.131 -2.746) (xy 1.129 -2.73) (xy 1.127 -2.719) (xy 1.123 -2.711)
				(xy 1.117 -2.705) (xy 1.098 -2.691) (xy 1.07 -2.682) (xy 1.032 -2.677) (xy 1.006 -2.677) (xy 0.972 -2.678)
				(xy 0.945 -2.682) (xy 0.924 -2.688) (xy 0.907 -2.699) (xy 0.9 -2.706) (xy 0.882 -2.723) (xy 0.834 -2.686)
				(xy 0.816 -2.672) (xy 0.801 -2.66) (xy 0.79 -2.652) (xy 0.787 -2.648) (xy 0.791 -2.639) (xy 0.801 -2.626)
				(xy 0.816 -2.612) (xy 0.832 -2.6) (xy 0.864 -2.581) (xy 0.902 -2.568) (xy 0.946 -2.559) (xy 0.98 -2.556)
				(xy 1.038 -2.556)
			)
			(stroke
				(width 0.01)
				(type solid)
			)
			(fill yes)
			(layer "B.Cu")
		)
		(fp_poly
			(pts
				(xy -1.521 -2.559) (xy -1.485 -2.562) (xy -1.454 -2.568) (xy -1.427 -2.577) (xy -1.401 -2.589) (xy -1.371 -2.61)
				(xy -1.345 -2.639) (xy -1.325 -2.67) (xy -1.321 -2.679) (xy -1.309 -2.71) (xy -1.309 -3.197) (xy -1.433 -3.2)
				(xy -1.433 -3.172) (xy -1.434 -3.157) (xy -1.435 -3.147) (xy -1.436 -3.144) (xy -1.44 -3.147) (xy -1.449 -3.156)
				(xy -1.453 -3.161) (xy -1.472 -3.178) (xy -1.496 -3.19) (xy -1.526 -3.198) (xy -1.563 -3.202) (xy -1.578 -3.203)
				(xy -1.603 -3.203) (xy -1.627 -3.203) (xy -1.647 -3.201) (xy -1.656 -3.2) (xy -1.686 -3.191) (xy -1.717 -3.176)
				(xy -1.746 -3.159) (xy -1.765 -3.143) (xy -1.79 -3.111) (xy -1.807 -3.075) (xy -1.816 -3.037) (xy -1.817 -2.998)
				(xy -1.817 -2.997) (xy -1.697 -2.997) (xy -1.696 -3.02) (xy -1.687 -3.042) (xy -1.67 -3.06) (xy -1.668 -3.062)
				(xy -1.654 -3.07) (xy -1.64 -3.076) (xy -1.624 -3.08) (xy -1.602 -3.081) (xy -1.574 -3.082) (xy -1.558 -3.082)
				(xy -1.529 -3.081) (xy -1.508 -3.08) (xy -1.494 -3.078) (xy -1.483 -3.075) (xy -1.474 -3.07) (xy -1.458 -3.058)
				(xy -1.447 -3.041) (xy -1.44 -3.017) (xy -1.435 -2.985) (xy -1.435 -2.977) (xy -1.432 -2.931) (xy -1.533 -2.931)
				(xy -1.568 -2.931) (xy -1.595 -2.931) (xy -1.615 -2.932) (xy -1.63 -2.934) (xy -1.641 -2.936) (xy -1.65 -2.938)
				(xy -1.655 -2.941) (xy -1.676 -2.955) (xy -1.69 -2.974) (xy -1.697 -2.997) (xy -1.817 -2.997) (xy -1.811 -2.96)
				(xy -1.797 -2.924) (xy -1.775 -2.892) (xy -1.747 -2.864) (xy -1.715 -2.845) (xy -1.7 -2.838) (xy -1.685 -2.833)
				(xy -1.668 -2.83) (xy -1.648 -2.827) (xy -1.623 -2.825) (xy -1.591 -2.824) (xy -1.551 -2.824) (xy -1.54 -2.824)
				(xy -1.432 -2.824) (xy -1.434 -2.776) (xy -1.436 -2.747) (xy -1.441 -2.726) (xy -1.448 -2.711) (xy -1.46 -2.699)
				(xy -1.474 -2.689) (xy -1.483 -2.685) (xy -1.492 -2.682) (xy -1.505 -2.68) (xy -1.524 -2.68) (xy -1.55 -2.679)
				(xy -1.56 -2.679) (xy -1.594 -2.68) (xy -1.62 -2.682) (xy -1.639 -2.686) (xy -1.654 -2.692) (xy -1.666 -2.701)
				(xy -1.675 -2.711) (xy -1.686 -2.724) (xy -1.735 -2.686) (xy -1.754 -2.672) (xy -1.769 -2.659) (xy -1.78 -2.65)
				(xy -1.784 -2.646) (xy -1.78 -2.64) (xy -1.77 -2.629) (xy -1.756 -2.616) (xy -1.74 -2.604) (xy -1.724 -2.592)
				(xy -1.711 -2.584) (xy -1.71 -2.583) (xy -1.688 -2.574) (xy -1.668 -2.566) (xy -1.647 -2.562) (xy -1.623 -2.559)
				(xy -1.593 -2.558) (xy -1.565 -2.558) (xy -1.521 -2.559)
			)
			(stroke
				(width 0.01)
				(type solid)
			)
			(fill yes)
			(layer "B.Cu")
		)
		(fp_poly
			(pts
				(xy 0.035 -2.777) (xy 0.047 -2.822) (xy 0.059 -2.864) (xy 0.069 -2.903) (xy 0.078 -2.936) (xy 0.086 -2.963)
				(xy 0.092 -2.984) (xy 0.095 -2.996) (xy 0.096 -2.999) (xy 0.098 -2.999) (xy 0.103 -2.991) (xy 0.109 -2.975)
				(xy 0.118 -2.95) (xy 0.129 -2.917) (xy 0.143 -2.874) (xy 0.152 -2.849) (xy 0.165 -2.807) (xy 0.179 -2.766)
				(xy 0.192 -2.726) (xy 0.204 -2.689) (xy 0.214 -2.658) (xy 0.221 -2.634) (xy 0.224 -2.627) (xy 0.244 -2.565)
				(xy 0.338 -2.565) (xy 0.406 -2.774) (xy 0.42 -2.819) (xy 0.434 -2.861) (xy 0.446 -2.899) (xy 0.457 -2.932)
				(xy 0.466 -2.96) (xy 0.473 -2.981) (xy 0.477 -2.993) (xy 0.478 -2.997) (xy 0.48 -2.998) (xy 0.482 -2.996)
				(xy 0.485 -2.99) (xy 0.49 -2.978) (xy 0.495 -2.96) (xy 0.502 -2.936) (xy 0.511 -2.905) (xy 0.523 -2.865)
				(xy 0.536 -2.817) (xy 0.543 -2.789) (xy 0.556 -2.744) (xy 0.568 -2.701) (xy 0.578 -2.663) (xy 0.587 -2.629)
				(xy 0.595 -2.602) (xy 0.601 -2.582) (xy 0.605 -2.57) (xy 0.606 -2.567) (xy 0.611 -2.566) (xy 0.625 -2.566)
				(xy 0.645 -2.566) (xy 0.669 -2.566) (xy 0.673 -2.566) (xy 0.739 -2.567) (xy 0.656 -2.827) (xy 0.64 -2.878)
				(xy 0.624 -2.928) (xy 0.609 -2.976) (xy 0.595 -3.02) (xy 0.582 -3.06) (xy 0.571 -3.094) (xy 0.563 -3.121)
				(xy 0.557 -3.139) (xy 0.556 -3.143) (xy 0.538 -3.2) (xy 0.425 -3.197) (xy 0.358 -2.975) (xy 0.341 -2.917)
				(xy 0.327 -2.87) (xy 0.315 -2.831) (xy 0.305 -2.801) (xy 0.297 -2.78) (xy 0.292 -2.766) (xy 0.289 -2.761)
				(xy 0.288 -2.761) (xy 0.286 -2.768) (xy 0.281 -2.783) (xy 0.274 -2.806) (xy 0.265 -2.836) (xy 0.254 -2.871)
				(xy 0.242 -2.911) (xy 0.23 -2.953) (xy 0.223 -2.976) (xy 0.21 -3.02) (xy 0.197 -3.062) (xy 0.186 -3.099)
				(xy 0.177 -3.132) (xy 0.169 -3.158) (xy 0.163 -3.177) (xy 0.16 -3.189) (xy 0.159 -3.191) (xy 0.157 -3.195)
				(xy 0.151 -3.198) (xy 0.141 -3.199) (xy 0.124 -3.2) (xy 0.101 -3.2) (xy 0.073 -3.199) (xy 0.055 -3.198)
				(xy 0.045 -3.196) (xy 0.043 -3.194) (xy 0.041 -3.188) (xy 0.036 -3.173) (xy 0.029 -3.15) (xy 0.019 -3.121)
				(xy 0.008 -3.084) (xy -0.006 -3.043) (xy -0.02 -2.996) (xy -0.036 -2.946) (xy -0.053 -2.893) (xy -0.057 -2.883)
				(xy -0.074 -2.83) (xy -0.09 -2.779) (xy -0.105 -2.732) (xy -0.119 -2.689) (xy -0.131 -2.652) (xy -0.141 -2.621)
				(xy -0.148 -2.596) (xy -0.154 -2.58) (xy -0.156 -2.572) (xy -0.156 -2.569) (xy -0.151 -2.567) (xy -0.14 -2.566)
				(xy -0.123 -2.565) (xy -0.096 -2.565) (xy -0.091 -2.565) (xy -0.023 -2.565) (xy 0.035 -2.777)
			)
			(stroke
				(width 0.01)
				(type solid)
			)
			(fill yes)
			(layer "B.Cu")
		)
		(fp_poly
			(pts
				(xy -2.065 -1.559) (xy -2.024 -1.576) (xy -1.986 -1.601) (xy -1.973 -1.612) (xy -1.957 -1.63) (xy -1.943 -1.649)
				(xy -1.932 -1.668) (xy -1.924 -1.69) (xy -1.918 -1.716) (xy -1.914 -1.747) (xy -1.911 -1.785) (xy -1.91 -1.831)
				(xy -1.91 -1.877) (xy -1.91 -1.93) (xy -1.912 -1.974) (xy -1.914 -2.011) (xy -1.919 -2.041) (xy -1.925 -2.067)
				(xy -1.934 -2.088) (xy -1.945 -2.107) (xy -1.959 -2.125) (xy -1.972 -2.139) (xy -1.993 -2.157) (xy -2.018 -2.173)
				(xy -2.031 -2.18) (xy -2.047 -2.188) (xy -2.06 -2.192) (xy -2.074 -2.195) (xy -2.091 -2.196) (xy -2.114 -2.197)
				(xy -2.122 -2.197) (xy -2.147 -2.196) (xy -2.165 -2.195) (xy -2.179 -2.193) (xy -2.191 -2.189) (xy -2.205 -2.183)
				(xy -2.21 -2.18) (xy -2.231 -2.169) (xy -2.251 -2.156) (xy -2.265 -2.146) (xy -2.286 -2.127) (xy -2.286 -2.627)
				(xy -2.266 -2.608) (xy -2.248 -2.595) (xy -2.227 -2.582) (xy -2.217 -2.577) (xy -2.173 -2.562) (xy -2.129 -2.556)
				(xy -2.086 -2.559) (xy -2.045 -2.57) (xy -2.007 -2.589) (xy -1.974 -2.616) (xy -1.946 -2.648) (xy -1.926 -2.687)
				(xy -1.919 -2.707) (xy -1.917 -2.715) (xy -1.915 -2.724) (xy -1.914 -2.737) (xy -1.913 -2.753) (xy -1.912 -2.774)
				(xy -1.911 -2.8) (xy -1.911 -2.833) (xy -1.911 -2.874) (xy -1.911 -2.923) (xy -1.911 -2.967) (xy -1.911 -3.2)
				(xy -2.035 -3.197) (xy -2.038 -2.984) (xy -2.038 -2.932) (xy -2.039 -2.889) (xy -2.039 -2.854) (xy -2.04 -2.826)
				(xy -2.041 -2.805) (xy -2.042 -2.788) (xy -2.043 -2.776) (xy -2.045 -2.767) (xy -2.046 -2.76) (xy -2.049 -2.755)
				(xy -2.051 -2.75) (xy -2.072 -2.721) (xy -2.098 -2.701) (xy -2.128 -2.688) (xy -2.161 -2.683) (xy -2.195 -2.687)
				(xy -2.22 -2.697) (xy -2.24 -2.71) (xy -2.259 -2.729) (xy -2.274 -2.75) (xy -2.278 -2.757) (xy -2.28 -2.765)
				(xy -2.281 -2.781) (xy -2.283 -2.806) (xy -2.284 -2.839) (xy -2.285 -2.881) (xy -2.286 -2.933) (xy -2.286 -2.984)
				(xy -2.289 -3.197) (xy -2.413 -3.2) (xy -2.413 -1.877) (xy -2.286 -1.877) (xy -2.285 -1.926) (xy -2.281 -1.966)
				(xy -2.274 -1.998) (xy -2.262 -2.024) (xy -2.247 -2.043) (xy -2.228 -2.058) (xy -2.215 -2.064) (xy -2.194 -2.07)
				(xy -2.168 -2.072) (xy -2.141 -2.071) (xy -2.117 -2.066) (xy -2.106 -2.063) (xy -2.079 -2.044) (xy -2.058 -2.019)
				(xy -2.05 -2.001) (xy -2.045 -1.984) (xy -2.042 -1.959) (xy -2.04 -1.929) (xy -2.038 -1.895) (xy -2.038 -1.861)
				(xy -2.039 -1.829) (xy -2.041 -1.8) (xy -2.044 -1.777) (xy -2.045 -1.772) (xy -2.057 -1.738) (xy -2.073 -1.712)
				(xy -2.094 -1.695) (xy -2.122 -1.684) (xy -2.156 -1.681) (xy -2.159 -1.681) (xy -2.192 -1.683) (xy -2.22 -1.691)
				(xy -2.243 -1.705) (xy -2.26 -1.725) (xy -2.273 -1.753) (xy -2.281 -1.788) (xy -2.285 -1.832) (xy -2.286 -1.877)
				(xy -2.413 -1.877) (xy -2.413 -1.559) (xy -2.286 -1.559) (xy -2.286 -1.62) (xy -2.26 -1.6) (xy -2.225 -1.577)
				(xy -2.19 -1.563) (xy -2.154 -1.554) (xy -2.109 -1.552) (xy -2.065 -1.559)
			)
			(stroke
				(width 0.01)
				(type solid)
			)
			(fill yes)
			(layer "B.Cu")
		)
		(fp_poly
			(pts
				(xy 0.063 3.201) (xy 0.118 3.201) (xy 0.164 3.201) (xy 0.202 3.2) (xy 0.233 3.2) (xy 0.258 3.2)
				(xy 0.277 3.199) (xy 0.292 3.198) (xy 0.302 3.197) (xy 0.309 3.196) (xy 0.314 3.195) (xy 0.317 3.193)
				(xy 0.319 3.192) (xy 0.321 3.189) (xy 0.324 3.183) (xy 0.327 3.174) (xy 0.33 3.161) (xy 0.334 3.144)
				(xy 0.339 3.12) (xy 0.345 3.091) (xy 0.352 3.054) (xy 0.361 3.01) (xy 0.371 2.958) (xy 0.382 2.897)
				(xy 0.385 2.878) (xy 0.395 2.824) (xy 0.405 2.772) (xy 0.414 2.724) (xy 0.423 2.68) (xy 0.43 2.642)
				(xy 0.437 2.61) (xy 0.442 2.586) (xy 0.446 2.569) (xy 0.448 2.562) (xy 0.456 2.55) (xy 0.464 2.544)
				(xy 0.476 2.539) (xy 0.495 2.53) (xy 0.521 2.519) (xy 0.552 2.506) (xy 0.587 2.492) (xy 0.624 2.477)
				(xy 0.664 2.461) (xy 0.704 2.445) (xy 0.743 2.43) (xy 0.78 2.415) (xy 0.814 2.402) (xy 0.843 2.391)
				(xy 0.868 2.382) (xy 0.885 2.376) (xy 0.895 2.373) (xy 0.896 2.373) (xy 0.911 2.376) (xy 0.931 2.386)
				(xy 0.948 2.397) (xy 0.962 2.406) (xy 0.983 2.421) (xy 1.011 2.44) (xy 1.043 2.462) (xy 1.079 2.487)
				(xy 1.118 2.513) (xy 1.158 2.541) (xy 1.198 2.568) (xy 1.238 2.595) (xy 1.275 2.621) (xy 1.309 2.644)
				(xy 1.338 2.665) (xy 1.362 2.681) (xy 1.377 2.691) (xy 1.398 2.705) (xy 1.418 2.717) (xy 1.433 2.725)
				(xy 1.442 2.728) (xy 1.443 2.728) (xy 1.448 2.726) (xy 1.456 2.72) (xy 1.468 2.71) (xy 1.486 2.694)
				(xy 1.508 2.673) (xy 1.535 2.647) (xy 1.568 2.614) (xy 1.608 2.575) (xy 1.654 2.53) (xy 1.675 2.509)
				(xy 1.721 2.462) (xy 1.761 2.422) (xy 1.794 2.388) (xy 1.822 2.36) (xy 1.844 2.337) (xy 1.862 2.318)
				(xy 1.875 2.304) (xy 1.884 2.293) (xy 1.89 2.284) (xy 1.893 2.279) (xy 1.894 2.275) (xy 1.892 2.269)
				(xy 1.886 2.257) (xy 1.875 2.239) (xy 1.86 2.215) (xy 1.839 2.183) (xy 1.814 2.145) (xy 1.783 2.1)
				(xy 1.747 2.046) (xy 1.721 2.009) (xy 1.69 1.964) (xy 1.661 1.921) (xy 1.634 1.88) (xy 1.609 1.844)
				(xy 1.588 1.811) (xy 1.57 1.785) (xy 1.557 1.764) (xy 1.549 1.75) (xy 1.546 1.743) (xy 1.547 1.735)
				(xy 1.552 1.719) (xy 1.56 1.696) (xy 1.571 1.667) (xy 1.585 1.634) (xy 1.6 1.597) (xy 1.616 1.557)
				(xy 1.633 1.516) (xy 1.651 1.476) (xy 1.668 1.436) (xy 1.685 1.398) (xy 1.701 1.363) (xy 1.715 1.333)
				(xy 1.727 1.309) (xy 1.736 1.291) (xy 1.742 1.281) (xy 1.744 1.279) (xy 1.751 1.277) (xy 1.767 1.273)
				(xy 1.791 1.268) (xy 1.822 1.261) (xy 1.86 1.254) (xy 1.903 1.245) (xy 1.951 1.236) (xy 2.002 1.226)
				(xy 2.049 1.217) (xy 2.103 1.207) (xy 2.154 1.198) (xy 2.201 1.188) (xy 2.244 1.18) (xy 2.281 1.173)
				(xy 2.311 1.166) (xy 2.335 1.161) (xy 2.35 1.157) (xy 2.355 1.156) (xy 2.367 1.148) (xy 2.367 0.834)
				(xy 2.367 0.768) (xy 2.367 0.712) (xy 2.367 0.664) (xy 2.366 0.625) (xy 2.366 0.592) (xy 2.365 0.566)
				(xy 2.364 0.546) (xy 2.363 0.531) (xy 2.361 0.52) (xy 2.358 0.512) (xy 2.355 0.507) (xy 2.352 0.504)
				(xy 2.348 0.503) (xy 2.343 0.501) (xy 2.34 0.501) (xy 2.333 0.499) (xy 2.317 0.496) (xy 2.293 0.492)
				(xy 2.261 0.486) (xy 2.224 0.479) (xy 2.181 0.471) (xy 2.134 0.462) (xy 2.084 0.453) (xy 2.054 0.448)
				(xy 2.002 0.438) (xy 1.953 0.429) (xy 1.907 0.42) (xy 1.866 0.412) (xy 1.831 0.404) (xy 1.802 0.398)
				(xy 1.78 0.394) (xy 1.767 0.391) (xy 1.764 0.39) (xy 1.76 0.387) (xy 1.757 0.384) (xy 1.753 0.379)
				(xy 1.748 0.371) (xy 1.742 0.36) (xy 1.735 0.344) (xy 1.726 0.324) (xy 1.715 0.297) (xy 1.701 0.264)
				(xy 1.685 0.223) (xy 1.665 0.174) (xy 1.653 0.145) (xy 1.63 0.086) (xy 1.61 0.037) (xy 1.594 -0.005)
				(xy 1.582 -0.038) (xy 1.572 -0.064) (xy 1.566 -0.084) (xy 1.562 -0.097) (xy 1.561 -0.104) (xy 1.562 -0.105)
				(xy 1.565 -0.111) (xy 1.574 -0.125) (xy 1.587 -0.146) (xy 1.604 -0.173) (xy 1.626 -0.205) (xy 1.65 -0.241)
				(xy 1.677 -0.281) (xy 1.706 -0.324) (xy 1.729 -0.358) (xy 1.768 -0.413) (xy 1.8 -0.461) (xy 1.827 -0.502)
				(xy 1.85 -0.535) (xy 1.867 -0.562) (xy 1.88 -0.583) (xy 1.889 -0.598) (xy 1.893 -0.608) (xy 1.894 -0.612)
				(xy 1.893 -0.616) (xy 1.89 -0.622) (xy 1.885 -0.63) (xy 1.876 -0.64) (xy 1.863 -0.655) (xy 1.846 -0.673)
				(xy 1.825 -0.695) (xy 1.798 -0.723) (xy 1.765 -0.756) (xy 1.727 -0.795) (xy 1.682 -0.839) (xy 1.635 -0.886)
				(xy 1.595 -0.926) (xy 1.561 -0.96) (xy 1.532 -0.989) (xy 1.508 -1.012) (xy 1.488 -1.03) (xy 1.473 -1.044)
				(xy 1.461 -1.054) (xy 1.452 -1.061) (xy 1.445 -1.065) (xy 1.44 -1.066) (xy 1.438 -1.066) (xy 1.433 -1.064)
				(xy 1.421 -1.055) (xy 1.401 -1.043) (xy 1.376 -1.026) (xy 1.345 -1.005) (xy 1.31 -0.981) (xy 1.27 -0.954)
				(xy 1.228 -0.925) (xy 1.193 -0.901) (xy 1.138 -0.864) (xy 1.089 -0.83) (xy 1.046 -0.802) (xy 1.01 -0.778)
				(xy 0.981 -0.759) (xy 0.96 -0.746) (xy 0.946 -0.738) (xy 0.94 -0.736) (xy 0.932 -0.738) (xy 0.917 -0.745)
				(xy 0.895 -0.755) (xy 0.869 -0.768) (xy 0.84 -0.783) (xy 0.816 -0.795) (xy 0.781 -0.814) (xy 0.753 -0.828)
				(xy 0.732 -0.838) (xy 0.717 -0.845) (xy 0.707 -0.849) (xy 0.699 -0.85) (xy 0.694 -0.849) (xy 0.691 -0.847)
				(xy 0.687 -0.84) (xy 0.682 -0.829) (xy 0.674 -0.814) (xy 0.665 -0.793) (xy 0.653 -0.767) (xy 0.639 -0.735)
				(xy 0.623 -0.696) (xy 0.604 -0.651) (xy 0.582 -0.598) (xy 0.556 -0.538) (xy 0.528 -0.469) (xy 0.496 -0.391)
				(xy 0.47 -0.329) (xy 0.436 -0.247) (xy 0.406 -0.173) (xy 0.379 -0.108) (xy 0.355 -0.05) (xy 0.335 0)
				(xy 0.317 0.043) (xy 0.303 0.079) (xy 0.291 0.11) (xy 0.281 0.135) (xy 0.273 0.155) (xy 0.268 0.171)
				(xy 0.264 0.183) (xy 0.262 0.191) (xy 0.262 0.196) (xy 0.262 0.198) (xy 0.269 0.207) (xy 0.283 0.219)
				(xy 0.302 0.233) (xy 0.303 0.234) (xy 0.354 0.268) (xy 0.398 0.3) (xy 0.435 0.331) (xy 0.469 0.363)
				(xy 0.5 0.397) (xy 0.507 0.405) (xy 0.556 0.472) (xy 0.596 0.543) (xy 0.627 0.619) (xy 0.643 0.672)
				(xy 0.651 0.718) (xy 0.657 0.77) (xy 0.66 0.824) (xy 0.659 0.878) (xy 0.654 0.927) (xy 0.652 0.936)
				(xy 0.634 1.015) (xy 0.607 1.09) (xy 0.571 1.161) (xy 0.528 1.227) (xy 0.477 1.287) (xy 0.419 1.341)
				(xy 0.355 1.387) (xy 0.285 1.426) (xy 0.21 1.456) (xy 0.205 1.458) (xy 0.131 1.477) (xy 0.054 1.487)
				(xy -0.025 1.489) (xy -0.103 1.482) (xy -0.178 1.466) (xy -0.206 1.458) (xy -0.281 1.428) (xy -0.351 1.39)
				(xy -0.416 1.344) (xy -0.474 1.29) (xy -0.526 1.23) (xy -0.571 1.164) (xy -0.607 1.093) (xy -0.63 1.034)
				(xy -0.649 0.96) (xy -0.659 0.883) (xy -0.661 0.804) (xy -0.654 0.726) (xy -0.638 0.651) (xy -0.63 0.623)
				(xy -0.618 0.591) (xy -0.602 0.554) (xy -0.584 0.518) (xy -0.566 0.485) (xy -0.553 0.463) (xy -0.509 0.407)
				(xy -0.457 0.352) (xy -0.397 0.299) (xy -0.33 0.25) (xy -0.289 0.224) (xy -0.273 0.212) (xy -0.263 0.2)
				(xy -0.262 0.197) (xy -0.263 0.19) (xy -0.268 0.175) (xy -0.277 0.151) (xy -0.288 0.121) (xy -0.302 0.084)
				(xy -0.319 0.042) (xy -0.338 -0.005) (xy -0.358 -0.056) (xy -0.381 -0.111) (xy -0.404 -0.168) (xy -0.428 -0.228)
				(xy -0.453 -0.288) (xy -0.478 -0.349) (xy -0.504 -0.41) (xy -0.529 -0.47) (xy -0.553 -0.527) (xy -0.576 -0.583)
				(xy -0.598 -0.635) (xy -0.619 -0.683) (xy -0.638 -0.727) (xy -0.655 -0.765) (xy -0.669 -0.797) (xy -0.68 -0.822)
				(xy -0.689 -0.839) (xy -0.694 -0.848) (xy -0.695 -0.849) (xy -0.699 -0.85) (xy -0.706 -0.849) (xy -0.717 -0.845)
				(xy -0.732 -0.839) (xy -0.752 -0.829) (xy -0.779 -0.815) (xy -0.814 -0.797) (xy -0.817 -0.795) (xy -0.848 -0.779)
				(xy -0.877 -0.764) (xy -0.902 -0.752) (xy -0.922 -0.743) (xy -0.936 -0.737) (xy -0.941 -0.736) (xy -0.949 -0.739)
				(xy -0.964 -0.748) (xy -0.987 -0.761) (xy -1.015 -0.78) (xy -1.05 -0.803) (xy -1.072 -0.818) (xy -1.138 -0.863)
				(xy -1.195 -0.903) (xy -1.245 -0.937) (xy -1.289 -0.966) (xy -1.325 -0.991) (xy -1.356 -1.012) (xy -1.381 -1.029)
				(xy -1.401 -1.042) (xy -1.416 -1.052) (xy -1.427 -1.059) (xy -1.435 -1.064) (xy -1.439 -1.066) (xy -1.44 -1.066)
				(xy -1.449 -1.064) (xy -1.453 -1.061) (xy -1.458 -1.057) (xy -1.47 -1.046) (xy -1.487 -1.029) (xy -1.509 -1.007)
				(xy -1.537 -0.98) (xy -1.568 -0.95) (xy -1.602 -0.915) (xy -1.639 -0.879) (xy -1.678 -0.84) (xy -1.678 -0.839)
				(xy -1.726 -0.792) (xy -1.767 -0.751) (xy -1.801 -0.716) (xy -1.829 -0.687) (xy -1.852 -0.663) (xy -1.869 -0.644)
				(xy -1.882 -0.63) (xy -1.89 -0.62) (xy -1.894 -0.613) (xy -1.895 -0.61) (xy -1.892 -0.603) (xy -1.884 -0.588)
				(xy -1.87 -0.565) (xy -1.85 -0.536) (xy -1.826 -0.499) (xy -1.797 -0.455) (xy -1.763 -0.405) (xy -1.73 -0.358)
				(xy -1.7 -0.313) (xy -1.671 -0.271) (xy -1.645 -0.232) (xy -1.621 -0.197) (xy -1.601 -0.166) (xy -1.584 -0.141)
				(xy -1.572 -0.121) (xy -1.565 -0.109) (xy -1.563 -0.105) (xy -1.563 -0.099) (xy -1.566 -0.087) (xy -1.572 -0.07)
				(xy -1.58 -0.045) (xy -1.592 -0.013) (xy -1.607 0.026) (xy -1.626 0.074) (xy -1.648 0.13) (xy -1.654 0.145)
				(xy -1.676 0.199) (xy -1.695 0.245) (xy -1.71 0.282) (xy -1.723 0.313) (xy -1.733 0.337) (xy -1.741 0.356)
				(xy -1.748 0.369) (xy -1.753 0.379) (xy -1.758 0.385) (xy -1.761 0.388) (xy -1.763 0.389) (xy -1.767 0.39)
				(xy -1.774 0.392) (xy -1.784 0.395) (xy -1.799 0.398) (xy -1.818 0.402) (xy -1.843 0.407) (xy -1.873 0.413)
				(xy -1.91 0.42) (xy -1.954 0.429) (xy -2.005 0.438) (xy -2.065 0.449) (xy -2.133 0.462) (xy -2.211 0.477)
				(xy -2.22 0.478) (xy -2.26 0.486) (xy -2.29 0.491) (xy -2.313 0.496) (xy -2.33 0.499) (xy -2.341 0.502)
				(xy -2.349 0.504) (xy -2.353 0.506) (xy -2.356 0.508) (xy -2.359 0.51) (xy -2.36 0.511) (xy -2.361 0.514)
				(xy -2.363 0.518) (xy -2.364 0.526) (xy -2.365 0.536) (xy -2.366 0.551) (xy -2.366 0.571) (xy -2.367 0.597)
				(xy -2.367 0.629) (xy -2.368 0.668) (xy -2.368 0.715) (xy -2.368 0.771) (xy -2.368 0.834) (xy -2.368 1.148)
				(xy -2.356 1.155) (xy -2.349 1.158) (xy -2.333 1.162) (xy -2.309 1.167) (xy -2.278 1.173) (xy -2.24 1.181)
				(xy -2.197 1.189) (xy -2.149 1.198) (xy -2.098 1.208) (xy -2.051 1.217) (xy -1.996 1.227) (xy -1.945 1.237)
				(xy -1.897 1.246) (xy -1.854 1.254) (xy -1.817 1.262) (xy -1.787 1.268) (xy -1.764 1.273) (xy -1.75 1.277)
				(xy -1.745 1.279) (xy -1.741 1.285) (xy -1.733 1.3) (xy -1.722 1.322) (xy -1.709 1.35) (xy -1.694 1.382)
				(xy -1.677 1.419) (xy -1.66 1.458) (xy -1.642 1.498) (xy -1.625 1.539) (xy -1.608 1.58) (xy -1.592 1.618)
				(xy -1.578 1.653) (xy -1.565 1.684) (xy -1.556 1.709) (xy -1.549 1.729) (xy -1.546 1.74) (xy -1.546 1.742)
				(xy -1.549 1.749) (xy -1.558 1.763) (xy -1.571 1.784) (xy -1.588 1.811) (xy -1.61 1.843) (xy -1.634 1.88)
				(xy -1.661 1.92) (xy -1.691 1.963) (xy -1.722 2.008) (xy -1.762 2.067) (xy -1.796 2.117) (xy -1.825 2.16)
				(xy -1.848 2.196) (xy -1.867 2.225) (xy -1.881 2.247) (xy -1.89 2.262) (xy -1.895 2.272) (xy -1.895 2.275)
				(xy -1.894 2.279) (xy -1.891 2.285) (xy -1.884 2.293) (xy -1.875 2.305) (xy -1.861 2.32) (xy -1.843 2.339)
				(xy -1.82 2.363) (xy -1.792 2.392) (xy -1.758 2.426) (xy -1.718 2.466) (xy -1.676 2.509) (xy -1.627 2.557)
				(xy -1.585 2.599) (xy -1.549 2.634) (xy -1.52 2.663) (xy -1.495 2.686) (xy -1.476 2.704) (xy -1.462 2.716)
				(xy -1.452 2.724) (xy -1.446 2.728) (xy -1.444 2.728) (xy -1.437 2.726) (xy -1.423 2.717) (xy -1.401 2.703)
				(xy -1.372 2.685) (xy -1.337 2.661) (xy -1.295 2.634) (xy -1.248 2.602) (xy -1.196 2.566) (xy -1.173 2.551)
				(xy -1.118 2.513) (xy -1.071 2.481) (xy -1.031 2.454) (xy -0.998 2.432) (xy -0.97 2.413) (xy -0.948 2.399)
				(xy -0.931 2.389) (xy -0.917 2.381) (xy -0.907 2.376) (xy -0.901 2.373) (xy -0.897 2.373) (xy -0.888 2.375)
				(xy -0.87 2.38) (xy -0.845 2.39) (xy -0.813 2.402) (xy -0.774 2.417) (xy -0.73 2.434) (xy -0.681 2.454)
				(xy -0.629 2.475) (xy -0.586 2.493) (xy -0.55 2.508) (xy -0.522 2.52) (xy -0.499 2.529) (xy -0.482 2.537)
				(xy -0.47 2.543) (xy -0.461 2.548) (xy -0.455 2.551) (xy -0.452 2.554) (xy -0.449 2.557) (xy -0.448 2.56)
				(xy -0.447 2.566) (xy -0.443 2.582) (xy -0.438 2.605) (xy -0.432 2.637) (xy -0.425 2.674) (xy -0.417 2.717)
				(xy -0.407 2.765) (xy -0.398 2.817) (xy -0.388 2.871) (xy -0.387 2.876) (xy -0.375 2.94) (xy -0.364 2.995)
				(xy -0.356 3.042) (xy -0.348 3.081) (xy -0.342 3.112) (xy -0.337 3.137) (xy -0.332 3.157) (xy -0.328 3.171)
				(xy -0.325 3.181) (xy -0.323 3.188) (xy -0.32 3.191) (xy -0.32 3.192) (xy -0.317 3.194) (xy -0.313 3.195)
				(xy -0.307 3.197) (xy -0.298 3.198) (xy -0.286 3.199) (xy -0.269 3.199) (xy -0.247 3.2) (xy -0.219 3.2)
				(xy -0.184 3.201) (xy -0.142 3.201) (xy -0.092 3.201) (xy -0.033 3.201) (xy -0.001 3.201) (xy 0.063 3.201)
			)
			(stroke
				(width 0.01)
				(type solid)
			)
			(fill yes)
			(layer "B.Cu")
		)
		(fp_poly
			(pts
				(xy -0.843 -2.558) (xy -0.815 -2.564) (xy -0.794 -2.572) (xy -0.773 -2.581) (xy -0.759 -2.589) (xy -0.738 -2.603)
				(xy -0.783 -2.658) (xy -0.8 -2.677) (xy -0.814 -2.694) (xy -0.825 -2.706) (xy -0.831 -2.712) (xy -0.832 -2.712)
				(xy -0.837 -2.71) (xy -0.847 -2.703) (xy -0.849 -2.702) (xy -0.874 -2.69) (xy -0.904 -2.684) (xy -0.935 -2.685)
				(xy -0.942 -2.686) (xy -0.975 -2.698) (xy -1.001 -2.717) (xy -1.02 -2.741) (xy -1.034 -2.766) (xy -1.039 -3.197)
				(xy -1.164 -3.2) (xy -1.164 -2.565) (xy -1.037 -2.565) (xy -1.037 -2.626) (xy -1.009 -2.604) (xy -0.972 -2.579)
				(xy -0.931 -2.563) (xy -0.887 -2.556) (xy -0.843 -2.558)
			)
			(stroke
				(width 0.01)
				(type solid)
			)
			(fill yes)
			(layer "B.Mask")
		)
		(fp_poly
			(pts
				(xy 1.889 -1.554) (xy 1.907 -1.559) (xy 1.927 -1.566) (xy 1.948 -1.574) (xy 1.966 -1.583) (xy 1.979 -1.592)
				(xy 1.984 -1.597) (xy 1.982 -1.604) (xy 1.974 -1.616) (xy 1.962 -1.633) (xy 1.946 -1.652) (xy 1.945 -1.654)
				(xy 1.929 -1.673) (xy 1.915 -1.689) (xy 1.906 -1.7) (xy 1.901 -1.706) (xy 1.896 -1.705) (xy 1.885 -1.7)
				(xy 1.873 -1.695) (xy 1.84 -1.683) (xy 1.808 -1.68) (xy 1.776 -1.685) (xy 1.747 -1.698) (xy 1.723 -1.717)
				(xy 1.704 -1.742) (xy 1.696 -1.763) (xy 1.695 -1.772) (xy 1.694 -1.79) (xy 1.693 -1.817) (xy 1.692 -1.85)
				(xy 1.692 -1.89) (xy 1.691 -1.934) (xy 1.691 -1.983) (xy 1.691 -2.194) (xy 1.559 -2.194) (xy 1.559 -1.559)
				(xy 1.691 -1.559) (xy 1.691 -1.626) (xy 1.71 -1.607) (xy 1.739 -1.585) (xy 1.775 -1.568) (xy 1.814 -1.556)
				(xy 1.855 -1.552) (xy 1.889 -1.554)
			)
			(stroke
				(width 0.01)
				(type solid)
			)
			(fill yes)
			(layer "B.Mask")
		)
		(fp_poly
			(pts
				(xy -0.837 -1.56) (xy -0.797 -1.576) (xy -0.761 -1.6) (xy -0.73 -1.63) (xy -0.706 -1.667) (xy -0.69 -1.709)
				(xy -0.687 -1.721) (xy -0.685 -1.734) (xy -0.684 -1.757) (xy -0.683 -1.79) (xy -0.682 -1.833) (xy -0.681 -1.884)
				(xy -0.681 -1.945) (xy -0.681 -1.971) (xy -0.681 -2.194) (xy -0.808 -2.194) (xy -0.809 -1.984) (xy -0.811 -1.774)
				(xy -0.826 -1.744) (xy -0.845 -1.716) (xy -0.868 -1.697) (xy -0.897 -1.686) (xy -0.925 -1.682) (xy -0.947 -1.682)
				(xy -0.967 -1.684) (xy -0.979 -1.686) (xy -1.001 -1.698) (xy -1.023 -1.716) (xy -1.041 -1.738) (xy -1.049 -1.752)
				(xy -1.052 -1.758) (xy -1.054 -1.765) (xy -1.056 -1.773) (xy -1.057 -1.783) (xy -1.058 -1.797) (xy -1.059 -1.815)
				(xy -1.06 -1.839) (xy -1.06 -1.869) (xy -1.061 -1.907) (xy -1.061 -1.953) (xy -1.061 -1.985) (xy -1.063 -2.194)
				(xy -1.189 -2.194) (xy -1.189 -1.559) (xy -1.062 -1.559) (xy -1.062 -1.625) (xy -1.033 -1.602) (xy -1.001 -1.579)
				(xy -0.969 -1.564) (xy -0.934 -1.555) (xy -0.927 -1.554) (xy -0.881 -1.553) (xy -0.837 -1.56)
			)
			(stroke
				(width 0.01)
				(type solid)
			)
			(fill yes)
			(layer "B.Mask")
		)
		(fp_poly
			(pts
				(xy 1.042 -1.769) (xy 1.043 -1.979) (xy 1.059 -2.009) (xy 1.077 -2.036) (xy 1.1 -2.056) (xy 1.129 -2.067)
				(xy 1.159 -2.071) (xy 1.193 -2.07) (xy 1.221 -2.063) (xy 1.245 -2.047) (xy 1.258 -2.034) (xy 1.266 -2.025)
				(xy 1.273 -2.016) (xy 1.278 -2.008) (xy 1.282 -1.997) (xy 1.286 -1.985) (xy 1.288 -1.969) (xy 1.29 -1.948)
				(xy 1.291 -1.922) (xy 1.292 -1.89) (xy 1.293 -1.85) (xy 1.293 -1.801) (xy 1.294 -1.766) (xy 1.295 -1.559)
				(xy 1.422 -1.559) (xy 1.422 -2.194) (xy 1.295 -2.194) (xy 1.295 -2.161) (xy 1.295 -2.144) (xy 1.293 -2.132)
				(xy 1.292 -2.128) (xy 1.287 -2.131) (xy 1.278 -2.14) (xy 1.271 -2.147) (xy 1.256 -2.159) (xy 1.236 -2.171)
				(xy 1.219 -2.181) (xy 1.202 -2.188) (xy 1.186 -2.193) (xy 1.17 -2.196) (xy 1.148 -2.197) (xy 1.135 -2.198)
				(xy 1.107 -2.198) (xy 1.087 -2.197) (xy 1.07 -2.194) (xy 1.059 -2.19) (xy 1.036 -2.181) (xy 1.019 -2.172)
				(xy 1.003 -2.161) (xy 0.985 -2.146) (xy 0.981 -2.141) (xy 0.952 -2.107) (xy 0.931 -2.068) (xy 0.92 -2.033)
				(xy 0.918 -2.019) (xy 0.917 -1.996) (xy 0.916 -1.963) (xy 0.915 -1.92) (xy 0.914 -1.869) (xy 0.914 -1.808)
				(xy 0.914 -1.782) (xy 0.914 -1.559) (xy 1.04 -1.559) (xy 1.042 -1.769)
			)
			(stroke
				(width 0.01)
				(type solid)
			)
			(fill yes)
			(layer "B.Mask")
		)
		(fp_poly
			(pts
				(xy 1.753 -2.563) (xy 1.768 -2.568) (xy 1.787 -2.577) (xy 1.804 -2.586) (xy 1.818 -2.595) (xy 1.826 -2.602)
				(xy 1.827 -2.606) (xy 1.824 -2.611) (xy 1.815 -2.621) (xy 1.803 -2.636) (xy 1.789 -2.654) (xy 1.775 -2.671)
				(xy 1.761 -2.688) (xy 1.749 -2.701) (xy 1.742 -2.71) (xy 1.739 -2.712) (xy 1.735 -2.71) (xy 1.724 -2.704)
				(xy 1.713 -2.698) (xy 1.697 -2.69) (xy 1.682 -2.686) (xy 1.664 -2.685) (xy 1.653 -2.685) (xy 1.618 -2.688)
				(xy 1.59 -2.699) (xy 1.566 -2.718) (xy 1.561 -2.723) (xy 1.554 -2.732) (xy 1.548 -2.74) (xy 1.544 -2.748)
				(xy 1.54 -2.758) (xy 1.537 -2.769) (xy 1.534 -2.785) (xy 1.533 -2.804) (xy 1.532 -2.829) (xy 1.531 -2.861)
				(xy 1.53 -2.899) (xy 1.53 -2.947) (xy 1.53 -2.988) (xy 1.528 -3.2) (xy 1.468 -3.2) (xy 1.444 -3.2)
				(xy 1.425 -3.199) (xy 1.411 -3.198) (xy 1.405 -3.197) (xy 1.404 -3.191) (xy 1.404 -3.176) (xy 1.403 -3.153)
				(xy 1.403 -3.122) (xy 1.402 -3.085) (xy 1.402 -3.042) (xy 1.402 -2.993) (xy 1.402 -2.941) (xy 1.402 -2.886)
				(xy 1.402 -2.565) (xy 1.529 -2.565) (xy 1.529 -2.595) (xy 1.529 -2.611) (xy 1.53 -2.623) (xy 1.532 -2.626)
				(xy 1.537 -2.623) (xy 1.547 -2.615) (xy 1.554 -2.608) (xy 1.588 -2.584) (xy 1.627 -2.567) (xy 1.669 -2.558)
				(xy 1.712 -2.556) (xy 1.753 -2.563)
			)
			(stroke
				(width 0.01)
				(type solid)
			)
			(fill yes)
			(layer "B.Mask")
		)
		(fp_poly
			(pts
				(xy 2.316 -1.557) (xy 2.365 -1.57) (xy 2.41 -1.593) (xy 2.453 -1.625) (xy 2.46 -1.631) (xy 2.491 -1.661)
				(xy 2.466 -1.684) (xy 2.448 -1.699) (xy 2.43 -1.715) (xy 2.419 -1.725) (xy 2.397 -1.743) (xy 2.376 -1.724)
				(xy 2.345 -1.701) (xy 2.312 -1.687) (xy 2.274 -1.681) (xy 2.265 -1.681) (xy 2.226 -1.684) (xy 2.195 -1.693)
				(xy 2.167 -1.708) (xy 2.159 -1.715) (xy 2.136 -1.741) (xy 2.118 -1.776) (xy 2.107 -1.817) (xy 2.103 -1.866)
				(xy 2.103 -1.876) (xy 2.106 -1.926) (xy 2.116 -1.97) (xy 2.132 -2.006) (xy 2.155 -2.034) (xy 2.184 -2.055)
				(xy 2.219 -2.067) (xy 2.259 -2.072) (xy 2.274 -2.071) (xy 2.309 -2.066) (xy 2.339 -2.056) (xy 2.366 -2.038)
				(xy 2.377 -2.028) (xy 2.386 -2.02) (xy 2.393 -2.016) (xy 2.4 -2.015) (xy 2.409 -2.018) (xy 2.42 -2.027)
				(xy 2.436 -2.041) (xy 2.456 -2.059) (xy 2.491 -2.092) (xy 2.476 -2.108) (xy 2.449 -2.132) (xy 2.416 -2.155)
				(xy 2.38 -2.174) (xy 2.35 -2.186) (xy 2.327 -2.193) (xy 2.306 -2.197) (xy 2.283 -2.199) (xy 2.259 -2.199)
				(xy 2.233 -2.198) (xy 2.209 -2.196) (xy 2.189 -2.193) (xy 2.182 -2.191) (xy 2.133 -2.173) (xy 2.089 -2.146)
				(xy 2.053 -2.112) (xy 2.023 -2.071) (xy 2.012 -2.051) (xy 2 -2.023) (xy 1.991 -1.999) (xy 1.984 -1.975)
				(xy 1.981 -1.948) (xy 1.979 -1.917) (xy 1.978 -1.879) (xy 1.978 -1.877) (xy 1.979 -1.838) (xy 1.98 -1.806)
				(xy 1.984 -1.78) (xy 1.99 -1.756) (xy 1.999 -1.731) (xy 2.011 -1.704) (xy 2.012 -1.701) (xy 2.039 -1.657)
				(xy 2.072 -1.62) (xy 2.111 -1.591) (xy 2.156 -1.57) (xy 2.207 -1.557) (xy 2.263 -1.552) (xy 2.316 -1.557)
			)
			(stroke
				(width 0.01)
				(type solid)
			)
			(fill yes)
			(layer "B.Mask")
		)
		(fp_poly
			(pts
				(xy -1.494 -1.56) (xy -1.447 -1.576) (xy -1.405 -1.6) (xy -1.368 -1.633) (xy -1.341 -1.668) (xy -1.326 -1.692)
				(xy -1.316 -1.716) (xy -1.308 -1.743) (xy -1.302 -1.774) (xy -1.299 -1.811) (xy -1.297 -1.845) (xy -1.294 -1.925)
				(xy -1.692 -1.925) (xy -1.692 -1.942) (xy -1.687 -1.977) (xy -1.673 -2.011) (xy -1.65 -2.039) (xy -1.626 -2.059)
				(xy -1.601 -2.071) (xy -1.572 -2.078) (xy -1.537 -2.079) (xy -1.497 -2.074) (xy -1.458 -2.06) (xy -1.422 -2.036)
				(xy -1.421 -2.036) (xy -1.402 -2.021) (xy -1.359 -2.057) (xy -1.342 -2.072) (xy -1.327 -2.085) (xy -1.317 -2.094)
				(xy -1.314 -2.098) (xy -1.316 -2.103) (xy -1.324 -2.113) (xy -1.338 -2.126) (xy -1.354 -2.139) (xy -1.372 -2.152)
				(xy -1.389 -2.163) (xy -1.399 -2.168) (xy -1.421 -2.178) (xy -1.445 -2.187) (xy -1.461 -2.191) (xy -1.488 -2.196)
				(xy -1.522 -2.199) (xy -1.557 -2.199) (xy -1.591 -2.196) (xy -1.62 -2.192) (xy -1.629 -2.19) (xy -1.677 -2.171)
				(xy -1.718 -2.146) (xy -1.752 -2.114) (xy -1.779 -2.074) (xy -1.8 -2.026) (xy -1.802 -2.02) (xy -1.81 -1.989)
				(xy -1.815 -1.951) (xy -1.818 -1.908) (xy -1.819 -1.865) (xy -1.818 -1.823) (xy -1.816 -1.804) (xy -1.692 -1.804)
				(xy -1.692 -1.818) (xy -1.428 -1.818) (xy -1.428 -1.801) (xy -1.432 -1.775) (xy -1.442 -1.748) (xy -1.457 -1.722)
				(xy -1.469 -1.707) (xy -1.495 -1.688) (xy -1.526 -1.676) (xy -1.56 -1.672) (xy -1.593 -1.676) (xy -1.619 -1.685)
				(xy -1.646 -1.704) (xy -1.668 -1.73) (xy -1.683 -1.76) (xy -1.691 -1.792) (xy -1.692 -1.804) (xy -1.816 -1.804)
				(xy -1.814 -1.786) (xy -1.812 -1.777) (xy -1.797 -1.724) (xy -1.775 -1.676) (xy -1.747 -1.636) (xy -1.713 -1.603)
				(xy -1.673 -1.578) (xy -1.629 -1.561) (xy -1.597 -1.554) (xy -1.544 -1.552) (xy -1.494 -1.56)
			)
			(stroke
				(width 0.01)
				(type solid)
			)
			(fill yes)
			(layer "B.Mask")
		)
		(fp_poly
			(pts
				(xy 2.835 -1.557) (xy 2.883 -1.57) (xy 2.926 -1.592) (xy 2.964 -1.621) (xy 2.996 -1.657) (xy 3.021 -1.699)
				(xy 3.038 -1.747) (xy 3.04 -1.757) (xy 3.043 -1.776) (xy 3.045 -1.802) (xy 3.047 -1.832) (xy 3.047 -1.858)
				(xy 3.047 -1.925) (xy 2.65 -1.925) (xy 2.653 -1.951) (xy 2.663 -1.991) (xy 2.68 -2.024) (xy 2.703 -2.049)
				(xy 2.733 -2.067) (xy 2.77 -2.077) (xy 2.801 -2.079) (xy 2.845 -2.075) (xy 2.883 -2.063) (xy 2.916 -2.042)
				(xy 2.92 -2.039) (xy 2.929 -2.031) (xy 2.935 -2.026) (xy 2.941 -2.025) (xy 2.949 -2.027) (xy 2.959 -2.034)
				(xy 2.974 -2.047) (xy 2.994 -2.064) (xy 3.01 -2.078) (xy 3.023 -2.088) (xy 3.03 -2.095) (xy 3.032 -2.096)
				(xy 3.03 -2.1) (xy 3.022 -2.11) (xy 3.01 -2.122) (xy 3.009 -2.123) (xy 2.98 -2.147) (xy 2.945 -2.169)
				(xy 2.906 -2.185) (xy 2.887 -2.191) (xy 2.861 -2.196) (xy 2.828 -2.198) (xy 2.793 -2.198) (xy 2.759 -2.197)
				(xy 2.729 -2.193) (xy 2.721 -2.191) (xy 2.675 -2.175) (xy 2.634 -2.15) (xy 2.599 -2.118) (xy 2.569 -2.077)
				(xy 2.547 -2.029) (xy 2.536 -1.996) (xy 2.532 -1.973) (xy 2.529 -1.942) (xy 2.527 -1.906) (xy 2.527 -1.869)
				(xy 2.528 -1.832) (xy 2.529 -1.818) (xy 2.65 -1.818) (xy 2.922 -1.818) (xy 2.918 -1.799) (xy 2.908 -1.758)
				(xy 2.891 -1.725) (xy 2.869 -1.7) (xy 2.84 -1.683) (xy 2.826 -1.678) (xy 2.788 -1.672) (xy 2.753 -1.675)
				(xy 2.722 -1.687) (xy 2.695 -1.706) (xy 2.674 -1.734) (xy 2.659 -1.768) (xy 2.654 -1.794) (xy 2.65 -1.818)
				(xy 2.529 -1.818) (xy 2.53 -1.798) (xy 2.534 -1.769) (xy 2.536 -1.76) (xy 2.554 -1.707) (xy 2.578 -1.662)
				(xy 2.609 -1.624) (xy 2.645 -1.593) (xy 2.687 -1.571) (xy 2.734 -1.557) (xy 2.783 -1.553) (xy 2.835 -1.557)
			)
			(stroke
				(width 0.01)
				(type solid)
			)
			(fill yes)
			(layer "B.Mask")
		)
		(fp_poly
			(pts
				(xy 2.148 -2.561) (xy 2.193 -2.574) (xy 2.235 -2.595) (xy 2.273 -2.623) (xy 2.304 -2.657) (xy 2.326 -2.691)
				(xy 2.338 -2.718) (xy 2.346 -2.745) (xy 2.352 -2.774) (xy 2.355 -2.808) (xy 2.357 -2.85) (xy 2.357 -2.858)
				(xy 2.357 -2.931) (xy 1.96 -2.931) (xy 1.963 -2.955) (xy 1.973 -2.993) (xy 1.991 -3.026) (xy 2.015 -3.053)
				(xy 2.039 -3.069) (xy 2.057 -3.076) (xy 2.08 -3.08) (xy 2.103 -3.082) (xy 2.144 -3.081) (xy 2.18 -3.071)
				(xy 2.214 -3.054) (xy 2.227 -3.045) (xy 2.24 -3.035) (xy 2.25 -3.029) (xy 2.253 -3.027) (xy 2.258 -3.03)
				(xy 2.269 -3.039) (xy 2.284 -3.05) (xy 2.3 -3.064) (xy 2.315 -3.078) (xy 2.329 -3.09) (xy 2.338 -3.099)
				(xy 2.341 -3.103) (xy 2.337 -3.11) (xy 2.327 -3.121) (xy 2.312 -3.134) (xy 2.294 -3.148) (xy 2.276 -3.161)
				(xy 2.259 -3.171) (xy 2.252 -3.175) (xy 2.204 -3.192) (xy 2.152 -3.202) (xy 2.098 -3.204) (xy 2.046 -3.198)
				(xy 2.032 -3.195) (xy 1.984 -3.178) (xy 1.943 -3.154) (xy 1.909 -3.123) (xy 1.881 -3.084) (xy 1.859 -3.037)
				(xy 1.847 -3.003) (xy 1.841 -2.972) (xy 1.838 -2.934) (xy 1.836 -2.893) (xy 1.837 -2.851) (xy 1.839 -2.824)
				(xy 1.96 -2.824) (xy 2.23 -2.824) (xy 2.23 -2.813) (xy 2.225 -2.783) (xy 2.214 -2.753) (xy 2.196 -2.725)
				(xy 2.175 -2.702) (xy 2.151 -2.686) (xy 2.128 -2.68) (xy 2.101 -2.677) (xy 2.072 -2.678) (xy 2.051 -2.683)
				(xy 2.023 -2.696) (xy 2 -2.717) (xy 1.981 -2.746) (xy 1.968 -2.779) (xy 1.963 -2.8) (xy 1.96 -2.824)
				(xy 1.839 -2.824) (xy 1.839 -2.811) (xy 1.844 -2.776) (xy 1.848 -2.76) (xy 1.866 -2.708) (xy 1.889 -2.663)
				(xy 1.919 -2.627) (xy 1.954 -2.598) (xy 1.996 -2.575) (xy 2.007 -2.571) (xy 2.054 -2.559) (xy 2.101 -2.556)
				(xy 2.148 -2.561)
			)
			(stroke
				(width 0.01)
				(type solid)
			)
			(fill yes)
			(layer "B.Mask")
		)
		(fp_poly
			(pts
				(xy -2.733 -1.557) (xy -2.685 -1.57) (xy -2.642 -1.592) (xy -2.604 -1.622) (xy -2.581 -1.649) (xy -2.562 -1.676)
				(xy -2.548 -1.706) (xy -2.537 -1.739) (xy -2.53 -1.777) (xy -2.527 -1.821) (xy -2.526 -1.873) (xy -2.527 -1.907)
				(xy -2.529 -1.956) (xy -2.534 -1.997) (xy -2.542 -2.031) (xy -2.553 -2.06) (xy -2.567 -2.086) (xy -2.587 -2.111)
				(xy -2.603 -2.129) (xy -2.637 -2.158) (xy -2.673 -2.178) (xy -2.714 -2.192) (xy -2.76 -2.198) (xy -2.789 -2.199)
				(xy -2.813 -2.198) (xy -2.835 -2.196) (xy -2.852 -2.194) (xy -2.857 -2.194) (xy -2.898 -2.179) (xy -2.937 -2.155)
				(xy -2.97 -2.126) (xy -2.993 -2.101) (xy -3.011 -2.077) (xy -3.024 -2.051) (xy -3.034 -2.022) (xy -3.041 -1.988)
				(xy -3.045 -1.947) (xy -3.047 -1.91) (xy -3.047 -1.882) (xy -2.919 -1.882) (xy -2.919 -1.968) (xy -2.903 -2.001)
				(xy -2.885 -2.031) (xy -2.863 -2.051) (xy -2.837 -2.064) (xy -2.804 -2.07) (xy -2.779 -2.07) (xy -2.755 -2.069)
				(xy -2.737 -2.065) (xy -2.722 -2.058) (xy -2.717 -2.055) (xy -2.697 -2.041) (xy -2.681 -2.025) (xy -2.67 -2.004)
				(xy -2.662 -1.978) (xy -2.657 -1.945) (xy -2.654 -1.903) (xy -2.654 -1.899) (xy -2.653 -1.848) (xy -2.656 -1.806)
				(xy -2.662 -1.772) (xy -2.673 -1.744) (xy -2.687 -1.722) (xy -2.707 -1.705) (xy -2.723 -1.695) (xy -2.755 -1.684)
				(xy -2.788 -1.68) (xy -2.821 -1.684) (xy -2.851 -1.695) (xy -2.877 -1.713) (xy -2.892 -1.729) (xy -2.901 -1.745)
				(xy -2.908 -1.76) (xy -2.913 -1.778) (xy -2.916 -1.8) (xy -2.918 -1.828) (xy -2.919 -1.864) (xy -2.919 -1.882)
				(xy -3.047 -1.882) (xy -3.048 -1.844) (xy -3.043 -1.786) (xy -3.034 -1.736) (xy -3.021 -1.695) (xy -3.004 -1.664)
				(xy -2.972 -1.624) (xy -2.935 -1.594) (xy -2.893 -1.571) (xy -2.846 -1.558) (xy -2.794 -1.553) (xy -2.787 -1.553)
				(xy -2.733 -1.557)
			)
			(stroke
				(width 0.01)
				(type solid)
			)
			(fill yes)
			(layer "B.Mask")
		)
		(fp_poly
			(pts
				(xy -0.229 -3.2) (xy -0.354 -3.197) (xy -0.355 -3.165) (xy -0.357 -3.133) (xy -0.374 -3.148) (xy -0.411 -3.175)
				(xy -0.453 -3.193) (xy -0.497 -3.203) (xy -0.542 -3.204) (xy -0.585 -3.195) (xy -0.586 -3.195) (xy -0.621 -3.181)
				(xy -0.651 -3.16) (xy -0.673 -3.141) (xy -0.689 -3.123) (xy -0.702 -3.106) (xy -0.712 -3.086) (xy -0.72 -3.064)
				(xy -0.726 -3.038) (xy -0.73 -3.007) (xy -0.732 -2.968) (xy -0.733 -2.922) (xy -0.733 -2.88) (xy -0.602 -2.88)
				(xy -0.602 -2.915) (xy -0.602 -2.942) (xy -0.601 -2.962) (xy -0.6 -2.977) (xy -0.598 -2.988) (xy -0.596 -2.998)
				(xy -0.592 -3.007) (xy -0.591 -3.01) (xy -0.574 -3.039) (xy -0.552 -3.059) (xy -0.525 -3.071) (xy -0.492 -3.076)
				(xy -0.472 -3.076) (xy -0.442 -3.072) (xy -0.418 -3.063) (xy -0.398 -3.048) (xy -0.382 -3.029) (xy -0.371 -3.004)
				(xy -0.363 -2.972) (xy -0.358 -2.933) (xy -0.356 -2.885) (xy -0.356 -2.88) (xy -0.358 -2.828) (xy -0.363 -2.785)
				(xy -0.373 -2.75) (xy -0.387 -2.724) (xy -0.406 -2.704) (xy -0.43 -2.692) (xy -0.46 -2.686) (xy -0.483 -2.685)
				(xy -0.517 -2.687) (xy -0.544 -2.696) (xy -0.565 -2.711) (xy -0.583 -2.734) (xy -0.591 -2.751) (xy -0.595 -2.76)
				(xy -0.598 -2.769) (xy -0.6 -2.779) (xy -0.601 -2.793) (xy -0.602 -2.811) (xy -0.602 -2.836) (xy -0.602 -2.869)
				(xy -0.602 -2.88) (xy -0.733 -2.88) (xy -0.733 -2.827) (xy -0.732 -2.783) (xy -0.729 -2.746) (xy -0.725 -2.716)
				(xy -0.719 -2.691) (xy -0.71 -2.67) (xy -0.699 -2.651) (xy -0.685 -2.633) (xy -0.668 -2.616) (xy -0.668 -2.615)
				(xy -0.632 -2.587) (xy -0.592 -2.567) (xy -0.55 -2.557) (xy -0.506 -2.556) (xy -0.463 -2.564) (xy -0.421 -2.582)
				(xy -0.411 -2.587) (xy -0.394 -2.598) (xy -0.377 -2.61) (xy -0.373 -2.614) (xy -0.356 -2.627) (xy -0.356 -2.306)
				(xy -0.229 -2.306) (xy -0.229 -3.2)
			)
			(stroke
				(width 0.01)
				(type solid)
			)
			(fill yes)
			(layer "B.Mask")
		)
		(fp_poly
			(pts
				(xy 0.605 -1.558) (xy 0.651 -1.574) (xy 0.694 -1.598) (xy 0.728 -1.627) (xy 0.75 -1.652) (xy 0.768 -1.678)
				(xy 0.781 -1.707) (xy 0.791 -1.739) (xy 0.797 -1.777) (xy 0.801 -1.822) (xy 0.802 -1.876) (xy 0.802 -1.877)
				(xy 0.801 -1.929) (xy 0.798 -1.973) (xy 0.792 -2.009) (xy 0.784 -2.04) (xy 0.774 -2.062) (xy 0.748 -2.103)
				(xy 0.715 -2.139) (xy 0.675 -2.167) (xy 0.632 -2.187) (xy 0.626 -2.189) (xy 0.599 -2.195) (xy 0.567 -2.198)
				(xy 0.532 -2.199) (xy 0.499 -2.197) (xy 0.471 -2.193) (xy 0.466 -2.192) (xy 0.428 -2.177) (xy 0.391 -2.155)
				(xy 0.359 -2.129) (xy 0.354 -2.123) (xy 0.332 -2.098) (xy 0.316 -2.073) (xy 0.303 -2.047) (xy 0.294 -2.017)
				(xy 0.287 -1.983) (xy 0.284 -1.943) (xy 0.282 -1.894) (xy 0.282 -1.877) (xy 0.409 -1.877) (xy 0.41 -1.918)
				(xy 0.412 -1.95) (xy 0.416 -1.976) (xy 0.423 -1.997) (xy 0.432 -2.015) (xy 0.445 -2.03) (xy 0.451 -2.037)
				(xy 0.471 -2.054) (xy 0.491 -2.064) (xy 0.514 -2.07) (xy 0.543 -2.072) (xy 0.569 -2.07) (xy 0.59 -2.065)
				(xy 0.601 -2.06) (xy 0.625 -2.047) (xy 0.642 -2.031) (xy 0.656 -2.009) (xy 0.661 -1.998) (xy 0.665 -1.989)
				(xy 0.668 -1.98) (xy 0.67 -1.969) (xy 0.671 -1.954) (xy 0.672 -1.935) (xy 0.673 -1.909) (xy 0.673 -1.877)
				(xy 0.673 -1.842) (xy 0.672 -1.817) (xy 0.671 -1.798) (xy 0.67 -1.784) (xy 0.668 -1.773) (xy 0.665 -1.764)
				(xy 0.661 -1.755) (xy 0.647 -1.73) (xy 0.632 -1.712) (xy 0.612 -1.698) (xy 0.601 -1.693) (xy 0.569 -1.683)
				(xy 0.535 -1.681) (xy 0.501 -1.686) (xy 0.471 -1.7) (xy 0.447 -1.719) (xy 0.434 -1.736) (xy 0.424 -1.753)
				(xy 0.417 -1.774) (xy 0.412 -1.8) (xy 0.41 -1.833) (xy 0.409 -1.873) (xy 0.409 -1.877) (xy 0.282 -1.877)
				(xy 0.283 -1.824) (xy 0.286 -1.78) (xy 0.292 -1.742) (xy 0.301 -1.711) (xy 0.313 -1.683) (xy 0.33 -1.657)
				(xy 0.35 -1.633) (xy 0.351 -1.632) (xy 0.385 -1.601) (xy 0.42 -1.578) (xy 0.46 -1.563) (xy 0.505 -1.554)
				(xy 0.555 -1.551) (xy 0.605 -1.558)
			)
			(stroke
				(width 0.01)
				(type solid)
			)
			(fill yes)
			(layer "B.Mask")
		)
		(fp_poly
			(pts
				(xy 0.004 -1.556) (xy 0.054 -1.566) (xy 0.102 -1.582) (xy 0.146 -1.605) (xy 0.154 -1.61) (xy 0.193 -1.636)
				(xy 0.178 -1.655) (xy 0.166 -1.668) (xy 0.152 -1.686) (xy 0.138 -1.7) (xy 0.114 -1.727) (xy 0.07 -1.705)
				(xy 0.032 -1.688) (xy -0.007 -1.677) (xy -0.044 -1.672) (xy -0.079 -1.672) (xy -0.11 -1.678) (xy -0.136 -1.69)
				(xy -0.154 -1.707) (xy -0.162 -1.724) (xy -0.164 -1.745) (xy -0.164 -1.761) (xy -0.159 -1.772) (xy -0.15 -1.782)
				(xy -0.149 -1.783) (xy -0.139 -1.791) (xy -0.128 -1.797) (xy -0.114 -1.802) (xy -0.095 -1.805) (xy -0.07 -1.808)
				(xy -0.037 -1.811) (xy -0.02 -1.813) (xy 0.027 -1.817) (xy 0.065 -1.823) (xy 0.096 -1.832) (xy 0.122 -1.842)
				(xy 0.14 -1.854) (xy 0.166 -1.879) (xy 0.186 -1.91) (xy 0.2 -1.947) (xy 0.206 -1.987) (xy 0.206 -2.018)
				(xy 0.198 -2.06) (xy 0.181 -2.097) (xy 0.155 -2.129) (xy 0.122 -2.156) (xy 0.08 -2.177) (xy 0.042 -2.189)
				(xy 0.005 -2.196) (xy -0.038 -2.199) (xy -0.083 -2.198) (xy -0.125 -2.194) (xy -0.153 -2.189) (xy -0.177 -2.181)
				(xy -0.204 -2.171) (xy -0.229 -2.16) (xy -0.232 -2.159) (xy -0.251 -2.148) (xy -0.272 -2.136) (xy -0.292 -2.122)
				(xy -0.309 -2.109) (xy -0.323 -2.098) (xy -0.33 -2.09) (xy -0.331 -2.088) (xy -0.327 -2.084) (xy -0.318 -2.073)
				(xy -0.304 -2.059) (xy -0.288 -2.043) (xy -0.246 -2) (xy -0.221 -2.021) (xy -0.184 -2.047) (xy -0.145 -2.065)
				(xy -0.102 -2.075) (xy -0.053 -2.079) (xy -0.049 -2.079) (xy -0.023 -2.079) (xy -0.004 -2.078) (xy 0.011 -2.074)
				(xy 0.025 -2.069) (xy 0.029 -2.068) (xy 0.054 -2.052) (xy 0.071 -2.033) (xy 0.079 -2.01) (xy 0.078 -1.986)
				(xy 0.074 -1.975) (xy 0.068 -1.964) (xy 0.06 -1.956) (xy 0.048 -1.949) (xy 0.031 -1.944) (xy 0.007 -1.939)
				(xy -0.024 -1.935) (xy -0.052 -1.932) (xy -0.089 -1.929) (xy -0.119 -1.925) (xy -0.142 -1.921) (xy -0.16 -1.917)
				(xy -0.176 -1.912) (xy -0.192 -1.906) (xy -0.201 -1.901) (xy -0.235 -1.879) (xy -0.262 -1.85) (xy -0.28 -1.816)
				(xy -0.29 -1.776) (xy -0.292 -1.75) (xy -0.291 -1.727) (xy -0.289 -1.705) (xy -0.286 -1.689) (xy -0.286 -1.688)
				(xy -0.273 -1.659) (xy -0.253 -1.63) (xy -0.229 -1.604) (xy -0.221 -1.599) (xy -0.185 -1.577) (xy -0.143 -1.562)
				(xy -0.096 -1.554) (xy -0.047 -1.552) (xy 0.004 -1.556)
			)
			(stroke
				(width 0.01)
				(type solid)
			)
			(fill yes)
			(layer "B.Mask")
		)
		(fp_poly
			(pts
				(xy 1.038 -2.556) (xy 1.091 -2.563) (xy 1.137 -2.576) (xy 1.177 -2.595) (xy 1.209 -2.62) (xy 1.234 -2.65)
				(xy 1.242 -2.665) (xy 1.247 -2.677) (xy 1.251 -2.691) (xy 1.255 -2.708) (xy 1.258 -2.727) (xy 1.26 -2.751)
				(xy 1.262 -2.78) (xy 1.263 -2.815) (xy 1.263 -2.858) (xy 1.264 -2.908) (xy 1.263 -2.967) (xy 1.263 -2.989)
				(xy 1.262 -3.197) (xy 1.135 -3.197) (xy 1.133 -3.171) (xy 1.132 -3.144) (xy 1.119 -3.159) (xy 1.096 -3.179)
				(xy 1.065 -3.193) (xy 1.026 -3.202) (xy 0.98 -3.204) (xy 0.976 -3.204) (xy 0.955 -3.204) (xy 0.937 -3.203)
				(xy 0.925 -3.202) (xy 0.924 -3.201) (xy 0.879 -3.189) (xy 0.839 -3.17) (xy 0.806 -3.144) (xy 0.781 -3.113)
				(xy 0.763 -3.077) (xy 0.753 -3.037) (xy 0.753 -3.005) (xy 0.873 -3.005) (xy 0.874 -3.023) (xy 0.878 -3.035)
				(xy 0.887 -3.047) (xy 0.89 -3.05) (xy 0.903 -3.063) (xy 0.917 -3.072) (xy 0.935 -3.078) (xy 0.957 -3.081)
				(xy 0.986 -3.082) (xy 1.013 -3.082) (xy 1.043 -3.081) (xy 1.065 -3.079) (xy 1.08 -3.077) (xy 1.091 -3.073)
				(xy 1.096 -3.071) (xy 1.112 -3.058) (xy 1.123 -3.039) (xy 1.13 -3.012) (xy 1.132 -2.977) (xy 1.132 -2.975)
				(xy 1.132 -2.931) (xy 1.035 -2.931) (xy 0.999 -2.931) (xy 0.973 -2.931) (xy 0.953 -2.932) (xy 0.939 -2.934)
				(xy 0.928 -2.936) (xy 0.919 -2.939) (xy 0.916 -2.94) (xy 0.893 -2.954) (xy 0.88 -2.971) (xy 0.874 -2.994)
				(xy 0.873 -3.005) (xy 0.753 -3.005) (xy 0.753 -2.994) (xy 0.761 -2.951) (xy 0.768 -2.931) (xy 0.776 -2.915)
				(xy 0.786 -2.901) (xy 0.802 -2.884) (xy 0.804 -2.882) (xy 0.82 -2.867) (xy 0.835 -2.854) (xy 0.85 -2.845)
				(xy 0.867 -2.838) (xy 0.887 -2.833) (xy 0.912 -2.829) (xy 0.943 -2.827) (xy 0.982 -2.826) (xy 1.015 -2.825)
				(xy 1.133 -2.823) (xy 1.132 -2.771) (xy 1.131 -2.746) (xy 1.129 -2.73) (xy 1.127 -2.719) (xy 1.123 -2.711)
				(xy 1.117 -2.705) (xy 1.098 -2.691) (xy 1.07 -2.682) (xy 1.032 -2.677) (xy 1.006 -2.677) (xy 0.972 -2.678)
				(xy 0.945 -2.682) (xy 0.924 -2.688) (xy 0.907 -2.699) (xy 0.9 -2.706) (xy 0.882 -2.723) (xy 0.834 -2.686)
				(xy 0.816 -2.672) (xy 0.801 -2.66) (xy 0.79 -2.652) (xy 0.787 -2.648) (xy 0.791 -2.639) (xy 0.801 -2.626)
				(xy 0.816 -2.612) (xy 0.832 -2.6) (xy 0.864 -2.581) (xy 0.902 -2.568) (xy 0.946 -2.559) (xy 0.98 -2.556)
				(xy 1.038 -2.556)
			)
			(stroke
				(width 0.01)
				(type solid)
			)
			(fill yes)
			(layer "B.Mask")
		)
		(fp_poly
			(pts
				(xy -1.521 -2.559) (xy -1.485 -2.562) (xy -1.454 -2.568) (xy -1.427 -2.577) (xy -1.401 -2.589) (xy -1.371 -2.61)
				(xy -1.345 -2.639) (xy -1.325 -2.67) (xy -1.321 -2.679) (xy -1.309 -2.71) (xy -1.309 -3.197) (xy -1.433 -3.2)
				(xy -1.433 -3.172) (xy -1.434 -3.157) (xy -1.435 -3.147) (xy -1.436 -3.144) (xy -1.44 -3.147) (xy -1.449 -3.156)
				(xy -1.453 -3.161) (xy -1.472 -3.178) (xy -1.496 -3.19) (xy -1.526 -3.198) (xy -1.563 -3.202) (xy -1.578 -3.203)
				(xy -1.603 -3.203) (xy -1.627 -3.203) (xy -1.647 -3.201) (xy -1.656 -3.2) (xy -1.686 -3.191) (xy -1.717 -3.176)
				(xy -1.746 -3.159) (xy -1.765 -3.143) (xy -1.79 -3.111) (xy -1.807 -3.075) (xy -1.816 -3.037) (xy -1.817 -2.998)
				(xy -1.817 -2.997) (xy -1.697 -2.997) (xy -1.696 -3.02) (xy -1.687 -3.042) (xy -1.67 -3.06) (xy -1.668 -3.062)
				(xy -1.654 -3.07) (xy -1.64 -3.076) (xy -1.624 -3.08) (xy -1.602 -3.081) (xy -1.574 -3.082) (xy -1.558 -3.082)
				(xy -1.529 -3.081) (xy -1.508 -3.08) (xy -1.494 -3.078) (xy -1.483 -3.075) (xy -1.474 -3.07) (xy -1.458 -3.058)
				(xy -1.447 -3.041) (xy -1.44 -3.017) (xy -1.435 -2.985) (xy -1.435 -2.977) (xy -1.432 -2.931) (xy -1.533 -2.931)
				(xy -1.568 -2.931) (xy -1.595 -2.931) (xy -1.615 -2.932) (xy -1.63 -2.934) (xy -1.641 -2.936) (xy -1.65 -2.938)
				(xy -1.655 -2.941) (xy -1.676 -2.955) (xy -1.69 -2.974) (xy -1.697 -2.997) (xy -1.817 -2.997) (xy -1.811 -2.96)
				(xy -1.797 -2.924) (xy -1.775 -2.892) (xy -1.747 -2.864) (xy -1.715 -2.845) (xy -1.7 -2.838) (xy -1.685 -2.833)
				(xy -1.668 -2.83) (xy -1.648 -2.827) (xy -1.623 -2.825) (xy -1.591 -2.824) (xy -1.551 -2.824) (xy -1.54 -2.824)
				(xy -1.432 -2.824) (xy -1.434 -2.776) (xy -1.436 -2.747) (xy -1.441 -2.726) (xy -1.448 -2.711) (xy -1.46 -2.699)
				(xy -1.474 -2.689) (xy -1.483 -2.685) (xy -1.492 -2.682) (xy -1.505 -2.68) (xy -1.524 -2.68) (xy -1.55 -2.679)
				(xy -1.56 -2.679) (xy -1.594 -2.68) (xy -1.62 -2.682) (xy -1.639 -2.686) (xy -1.654 -2.692) (xy -1.666 -2.701)
				(xy -1.675 -2.711) (xy -1.686 -2.724) (xy -1.735 -2.686) (xy -1.754 -2.672) (xy -1.769 -2.659) (xy -1.78 -2.65)
				(xy -1.784 -2.646) (xy -1.78 -2.64) (xy -1.77 -2.629) (xy -1.756 -2.616) (xy -1.74 -2.604) (xy -1.724 -2.592)
				(xy -1.711 -2.584) (xy -1.71 -2.583) (xy -1.688 -2.574) (xy -1.668 -2.566) (xy -1.647 -2.562) (xy -1.623 -2.559)
				(xy -1.593 -2.558) (xy -1.565 -2.558) (xy -1.521 -2.559)
			)
			(stroke
				(width 0.01)
				(type solid)
			)
			(fill yes)
			(layer "B.Mask")
		)
		(fp_poly
			(pts
				(xy 0.035 -2.777) (xy 0.047 -2.822) (xy 0.059 -2.864) (xy 0.069 -2.903) (xy 0.078 -2.936) (xy 0.086 -2.963)
				(xy 0.092 -2.984) (xy 0.095 -2.996) (xy 0.096 -2.999) (xy 0.098 -2.999) (xy 0.103 -2.991) (xy 0.109 -2.975)
				(xy 0.118 -2.95) (xy 0.129 -2.917) (xy 0.143 -2.874) (xy 0.152 -2.849) (xy 0.165 -2.807) (xy 0.179 -2.766)
				(xy 0.192 -2.726) (xy 0.204 -2.689) (xy 0.214 -2.658) (xy 0.221 -2.634) (xy 0.224 -2.627) (xy 0.244 -2.565)
				(xy 0.338 -2.565) (xy 0.406 -2.774) (xy 0.42 -2.819) (xy 0.434 -2.861) (xy 0.446 -2.899) (xy 0.457 -2.932)
				(xy 0.466 -2.96) (xy 0.473 -2.981) (xy 0.477 -2.993) (xy 0.478 -2.997) (xy 0.48 -2.998) (xy 0.482 -2.996)
				(xy 0.485 -2.99) (xy 0.49 -2.978) (xy 0.495 -2.96) (xy 0.502 -2.936) (xy 0.511 -2.905) (xy 0.523 -2.865)
				(xy 0.536 -2.817) (xy 0.543 -2.789) (xy 0.556 -2.744) (xy 0.568 -2.701) (xy 0.578 -2.663) (xy 0.587 -2.629)
				(xy 0.595 -2.602) (xy 0.601 -2.582) (xy 0.605 -2.57) (xy 0.606 -2.567) (xy 0.611 -2.566) (xy 0.625 -2.566)
				(xy 0.645 -2.566) (xy 0.669 -2.566) (xy 0.673 -2.566) (xy 0.739 -2.567) (xy 0.656 -2.827) (xy 0.64 -2.878)
				(xy 0.624 -2.928) (xy 0.609 -2.976) (xy 0.595 -3.02) (xy 0.582 -3.06) (xy 0.571 -3.094) (xy 0.563 -3.121)
				(xy 0.557 -3.139) (xy 0.556 -3.143) (xy 0.538 -3.2) (xy 0.425 -3.197) (xy 0.358 -2.975) (xy 0.341 -2.917)
				(xy 0.327 -2.87) (xy 0.315 -2.831) (xy 0.305 -2.801) (xy 0.297 -2.78) (xy 0.292 -2.766) (xy 0.289 -2.761)
				(xy 0.288 -2.761) (xy 0.286 -2.768) (xy 0.281 -2.783) (xy 0.274 -2.806) (xy 0.265 -2.836) (xy 0.254 -2.871)
				(xy 0.242 -2.911) (xy 0.23 -2.953) (xy 0.223 -2.976) (xy 0.21 -3.02) (xy 0.197 -3.062) (xy 0.186 -3.099)
				(xy 0.177 -3.132) (xy 0.169 -3.158) (xy 0.163 -3.177) (xy 0.16 -3.189) (xy 0.159 -3.191) (xy 0.157 -3.195)
				(xy 0.151 -3.198) (xy 0.141 -3.199) (xy 0.124 -3.2) (xy 0.101 -3.2) (xy 0.073 -3.199) (xy 0.055 -3.198)
				(xy 0.045 -3.196) (xy 0.043 -3.194) (xy 0.041 -3.188) (xy 0.036 -3.173) (xy 0.029 -3.15) (xy 0.019 -3.121)
				(xy 0.008 -3.084) (xy -0.006 -3.043) (xy -0.02 -2.996) (xy -0.036 -2.946) (xy -0.053 -2.893) (xy -0.057 -2.883)
				(xy -0.074 -2.83) (xy -0.09 -2.779) (xy -0.105 -2.732) (xy -0.119 -2.689) (xy -0.131 -2.652) (xy -0.141 -2.621)
				(xy -0.148 -2.596) (xy -0.154 -2.58) (xy -0.156 -2.572) (xy -0.156 -2.569) (xy -0.151 -2.567) (xy -0.14 -2.566)
				(xy -0.123 -2.565) (xy -0.096 -2.565) (xy -0.091 -2.565) (xy -0.023 -2.565) (xy 0.035 -2.777)
			)
			(stroke
				(width 0.01)
				(type solid)
			)
			(fill yes)
			(layer "B.Mask")
		)
		(fp_poly
			(pts
				(xy -2.065 -1.559) (xy -2.024 -1.576) (xy -1.986 -1.601) (xy -1.973 -1.612) (xy -1.957 -1.63) (xy -1.943 -1.649)
				(xy -1.932 -1.668) (xy -1.924 -1.69) (xy -1.918 -1.716) (xy -1.914 -1.747) (xy -1.911 -1.785) (xy -1.91 -1.831)
				(xy -1.91 -1.877) (xy -1.91 -1.93) (xy -1.912 -1.974) (xy -1.914 -2.011) (xy -1.919 -2.041) (xy -1.925 -2.067)
				(xy -1.934 -2.088) (xy -1.945 -2.107) (xy -1.959 -2.125) (xy -1.972 -2.139) (xy -1.993 -2.157) (xy -2.018 -2.173)
				(xy -2.031 -2.18) (xy -2.047 -2.188) (xy -2.06 -2.192) (xy -2.074 -2.195) (xy -2.091 -2.196) (xy -2.114 -2.197)
				(xy -2.122 -2.197) (xy -2.147 -2.196) (xy -2.165 -2.195) (xy -2.179 -2.193) (xy -2.191 -2.189) (xy -2.205 -2.183)
				(xy -2.21 -2.18) (xy -2.231 -2.169) (xy -2.251 -2.156) (xy -2.265 -2.146) (xy -2.286 -2.127) (xy -2.286 -2.627)
				(xy -2.266 -2.608) (xy -2.248 -2.595) (xy -2.227 -2.582) (xy -2.217 -2.577) (xy -2.173 -2.562) (xy -2.129 -2.556)
				(xy -2.086 -2.559) (xy -2.045 -2.57) (xy -2.007 -2.589) (xy -1.974 -2.616) (xy -1.946 -2.648) (xy -1.926 -2.687)
				(xy -1.919 -2.707) (xy -1.917 -2.715) (xy -1.915 -2.724) (xy -1.914 -2.737) (xy -1.913 -2.753) (xy -1.912 -2.774)
				(xy -1.911 -2.8) (xy -1.911 -2.833) (xy -1.911 -2.874) (xy -1.911 -2.923) (xy -1.911 -2.967) (xy -1.911 -3.2)
				(xy -2.035 -3.197) (xy -2.038 -2.984) (xy -2.038 -2.932) (xy -2.039 -2.889) (xy -2.039 -2.854) (xy -2.04 -2.826)
				(xy -2.041 -2.805) (xy -2.042 -2.788) (xy -2.043 -2.776) (xy -2.045 -2.767) (xy -2.046 -2.76) (xy -2.049 -2.755)
				(xy -2.051 -2.75) (xy -2.072 -2.721) (xy -2.098 -2.701) (xy -2.128 -2.688) (xy -2.161 -2.683) (xy -2.195 -2.687)
				(xy -2.22 -2.697) (xy -2.24 -2.71) (xy -2.259 -2.729) (xy -2.274 -2.75) (xy -2.278 -2.757) (xy -2.28 -2.765)
				(xy -2.281 -2.781) (xy -2.283 -2.806) (xy -2.284 -2.839) (xy -2.285 -2.881) (xy -2.286 -2.933) (xy -2.286 -2.984)
				(xy -2.289 -3.197) (xy -2.413 -3.2) (xy -2.413 -1.877) (xy -2.286 -1.877) (xy -2.285 -1.926) (xy -2.281 -1.966)
				(xy -2.274 -1.998) (xy -2.262 -2.024) (xy -2.247 -2.043) (xy -2.228 -2.058) (xy -2.215 -2.064) (xy -2.194 -2.07)
				(xy -2.168 -2.072) (xy -2.141 -2.071) (xy -2.117 -2.066) (xy -2.106 -2.063) (xy -2.079 -2.044) (xy -2.058 -2.019)
				(xy -2.05 -2.001) (xy -2.045 -1.984) (xy -2.042 -1.959) (xy -2.04 -1.929) (xy -2.038 -1.895) (xy -2.038 -1.861)
				(xy -2.039 -1.829) (xy -2.041 -1.8) (xy -2.044 -1.777) (xy -2.045 -1.772) (xy -2.057 -1.738) (xy -2.073 -1.712)
				(xy -2.094 -1.695) (xy -2.122 -1.684) (xy -2.156 -1.681) (xy -2.159 -1.681) (xy -2.192 -1.683) (xy -2.22 -1.691)
				(xy -2.243 -1.705) (xy -2.26 -1.725) (xy -2.273 -1.753) (xy -2.281 -1.788) (xy -2.285 -1.832) (xy -2.286 -1.877)
				(xy -2.413 -1.877) (xy -2.413 -1.559) (xy -2.286 -1.559) (xy -2.286 -1.62) (xy -2.26 -1.6) (xy -2.225 -1.577)
				(xy -2.19 -1.563) (xy -2.154 -1.554) (xy -2.109 -1.552) (xy -2.065 -1.559)
			)
			(stroke
				(width 0.01)
				(type solid)
			)
			(fill yes)
			(layer "B.Mask")
		)
		(fp_poly
			(pts
				(xy 0.063 3.201) (xy 0.118 3.201) (xy 0.164 3.201) (xy 0.202 3.2) (xy 0.233 3.2) (xy 0.258 3.2)
				(xy 0.277 3.199) (xy 0.292 3.198) (xy 0.302 3.197) (xy 0.309 3.196) (xy 0.314 3.195) (xy 0.317 3.193)
				(xy 0.319 3.192) (xy 0.321 3.189) (xy 0.324 3.183) (xy 0.327 3.174) (xy 0.33 3.161) (xy 0.334 3.144)
				(xy 0.339 3.12) (xy 0.345 3.091) (xy 0.352 3.054) (xy 0.361 3.01) (xy 0.371 2.958) (xy 0.382 2.897)
				(xy 0.385 2.878) (xy 0.395 2.824) (xy 0.405 2.772) (xy 0.414 2.724) (xy 0.423 2.68) (xy 0.43 2.642)
				(xy 0.437 2.61) (xy 0.442 2.586) (xy 0.446 2.569) (xy 0.448 2.562) (xy 0.456 2.55) (xy 0.464 2.544)
				(xy 0.476 2.539) (xy 0.495 2.53) (xy 0.521 2.519) (xy 0.552 2.506) (xy 0.587 2.492) (xy 0.624 2.477)
				(xy 0.664 2.461) (xy 0.704 2.445) (xy 0.743 2.43) (xy 0.78 2.415) (xy 0.814 2.402) (xy 0.843 2.391)
				(xy 0.868 2.382) (xy 0.885 2.376) (xy 0.895 2.373) (xy 0.896 2.373) (xy 0.911 2.376) (xy 0.931 2.386)
				(xy 0.948 2.397) (xy 0.962 2.406) (xy 0.983 2.421) (xy 1.011 2.44) (xy 1.043 2.462) (xy 1.079 2.487)
				(xy 1.118 2.513) (xy 1.158 2.541) (xy 1.198 2.568) (xy 1.238 2.595) (xy 1.275 2.621) (xy 1.309 2.644)
				(xy 1.338 2.665) (xy 1.362 2.681) (xy 1.377 2.691) (xy 1.398 2.705) (xy 1.418 2.717) (xy 1.433 2.725)
				(xy 1.442 2.728) (xy 1.443 2.728) (xy 1.448 2.726) (xy 1.456 2.72) (xy 1.468 2.71) (xy 1.486 2.694)
				(xy 1.508 2.673) (xy 1.535 2.647) (xy 1.568 2.614) (xy 1.608 2.575) (xy 1.654 2.53) (xy 1.675 2.509)
				(xy 1.721 2.462) (xy 1.761 2.422) (xy 1.794 2.388) (xy 1.822 2.36) (xy 1.844 2.337) (xy 1.862 2.318)
				(xy 1.875 2.304) (xy 1.884 2.293) (xy 1.89 2.284) (xy 1.893 2.279) (xy 1.894 2.275) (xy 1.892 2.269)
				(xy 1.886 2.257) (xy 1.875 2.239) (xy 1.86 2.215) (xy 1.839 2.183) (xy 1.814 2.145) (xy 1.783 2.1)
				(xy 1.747 2.046) (xy 1.721 2.009) (xy 1.69 1.964) (xy 1.661 1.921) (xy 1.634 1.88) (xy 1.609 1.844)
				(xy 1.588 1.811) (xy 1.57 1.785) (xy 1.557 1.764) (xy 1.549 1.75) (xy 1.546 1.743) (xy 1.547 1.735)
				(xy 1.552 1.719) (xy 1.56 1.696) (xy 1.571 1.667) (xy 1.585 1.634) (xy 1.6 1.597) (xy 1.616 1.557)
				(xy 1.633 1.516) (xy 1.651 1.476) (xy 1.668 1.436) (xy 1.685 1.398) (xy 1.701 1.363) (xy 1.715 1.333)
				(xy 1.727 1.309) (xy 1.736 1.291) (xy 1.742 1.281) (xy 1.744 1.279) (xy 1.751 1.277) (xy 1.767 1.273)
				(xy 1.791 1.268) (xy 1.822 1.261) (xy 1.86 1.254) (xy 1.903 1.245) (xy 1.951 1.236) (xy 2.002 1.226)
				(xy 2.049 1.217) (xy 2.103 1.207) (xy 2.154 1.198) (xy 2.201 1.188) (xy 2.244 1.18) (xy 2.281 1.173)
				(xy 2.311 1.166) (xy 2.335 1.161) (xy 2.35 1.157) (xy 2.355 1.156) (xy 2.367 1.148) (xy 2.367 0.834)
				(xy 2.367 0.768) (xy 2.367 0.712) (xy 2.367 0.664) (xy 2.366 0.625) (xy 2.366 0.592) (xy 2.365 0.566)
				(xy 2.364 0.546) (xy 2.363 0.531) (xy 2.361 0.52) (xy 2.358 0.512) (xy 2.355 0.507) (xy 2.352 0.504)
				(xy 2.348 0.503) (xy 2.343 0.501) (xy 2.34 0.501) (xy 2.333 0.499) (xy 2.317 0.496) (xy 2.293 0.492)
				(xy 2.261 0.486) (xy 2.224 0.479) (xy 2.181 0.471) (xy 2.134 0.462) (xy 2.084 0.453) (xy 2.054 0.448)
				(xy 2.002 0.438) (xy 1.953 0.429) (xy 1.907 0.42) (xy 1.866 0.412) (xy 1.831 0.404) (xy 1.802 0.398)
				(xy 1.78 0.394) (xy 1.767 0.391) (xy 1.764 0.39) (xy 1.76 0.387) (xy 1.757 0.384) (xy 1.753 0.379)
				(xy 1.748 0.371) (xy 1.742 0.36) (xy 1.735 0.344) (xy 1.726 0.324) (xy 1.715 0.297) (xy 1.701 0.264)
				(xy 1.685 0.223) (xy 1.665 0.174) (xy 1.653 0.145) (xy 1.63 0.086) (xy 1.61 0.037) (xy 1.594 -0.005)
				(xy 1.582 -0.038) (xy 1.572 -0.064) (xy 1.566 -0.084) (xy 1.562 -0.097) (xy 1.561 -0.104) (xy 1.562 -0.105)
				(xy 1.565 -0.111) (xy 1.574 -0.125) (xy 1.587 -0.146) (xy 1.604 -0.173) (xy 1.626 -0.205) (xy 1.65 -0.241)
				(xy 1.677 -0.281) (xy 1.706 -0.324) (xy 1.729 -0.358) (xy 1.768 -0.413) (xy 1.8 -0.461) (xy 1.827 -0.502)
				(xy 1.85 -0.535) (xy 1.867 -0.562) (xy 1.88 -0.583) (xy 1.889 -0.598) (xy 1.893 -0.608) (xy 1.894 -0.612)
				(xy 1.893 -0.616) (xy 1.89 -0.622) (xy 1.885 -0.63) (xy 1.876 -0.64) (xy 1.863 -0.655) (xy 1.846 -0.673)
				(xy 1.825 -0.695) (xy 1.798 -0.723) (xy 1.765 -0.756) (xy 1.727 -0.795) (xy 1.682 -0.839) (xy 1.635 -0.886)
				(xy 1.595 -0.926) (xy 1.561 -0.96) (xy 1.532 -0.989) (xy 1.508 -1.012) (xy 1.488 -1.03) (xy 1.473 -1.044)
				(xy 1.461 -1.054) (xy 1.452 -1.061) (xy 1.445 -1.065) (xy 1.44 -1.066) (xy 1.438 -1.066) (xy 1.433 -1.064)
				(xy 1.421 -1.055) (xy 1.401 -1.043) (xy 1.376 -1.026) (xy 1.345 -1.005) (xy 1.31 -0.981) (xy 1.27 -0.954)
				(xy 1.228 -0.925) (xy 1.193 -0.901) (xy 1.138 -0.864) (xy 1.089 -0.83) (xy 1.046 -0.802) (xy 1.01 -0.778)
				(xy 0.981 -0.759) (xy 0.96 -0.746) (xy 0.946 -0.738) (xy 0.94 -0.736) (xy 0.932 -0.738) (xy 0.917 -0.745)
				(xy 0.895 -0.755) (xy 0.869 -0.768) (xy 0.84 -0.783) (xy 0.816 -0.795) (xy 0.781 -0.814) (xy 0.753 -0.828)
				(xy 0.732 -0.838) (xy 0.717 -0.845) (xy 0.707 -0.849) (xy 0.699 -0.85) (xy 0.694 -0.849) (xy 0.691 -0.847)
				(xy 0.687 -0.84) (xy 0.682 -0.829) (xy 0.674 -0.814) (xy 0.665 -0.793) (xy 0.653 -0.767) (xy 0.639 -0.735)
				(xy 0.623 -0.696) (xy 0.604 -0.651) (xy 0.582 -0.598) (xy 0.556 -0.538) (xy 0.528 -0.469) (xy 0.496 -0.391)
				(xy 0.47 -0.329) (xy 0.436 -0.247) (xy 0.406 -0.173) (xy 0.379 -0.108) (xy 0.355 -0.05) (xy 0.335 0)
				(xy 0.317 0.043) (xy 0.303 0.079) (xy 0.291 0.11) (xy 0.281 0.135) (xy 0.273 0.155) (xy 0.268 0.171)
				(xy 0.264 0.183) (xy 0.262 0.191) (xy 0.262 0.196) (xy 0.262 0.198) (xy 0.269 0.207) (xy 0.283 0.219)
				(xy 0.302 0.233) (xy 0.303 0.234) (xy 0.354 0.268) (xy 0.398 0.3) (xy 0.435 0.331) (xy 0.469 0.363)
				(xy 0.5 0.397) (xy 0.507 0.405) (xy 0.556 0.472) (xy 0.596 0.543) (xy 0.627 0.619) (xy 0.643 0.672)
				(xy 0.651 0.718) (xy 0.657 0.77) (xy 0.66 0.824) (xy 0.659 0.878) (xy 0.654 0.927) (xy 0.652 0.936)
				(xy 0.634 1.015) (xy 0.607 1.09) (xy 0.571 1.161) (xy 0.528 1.227) (xy 0.477 1.287) (xy 0.419 1.341)
				(xy 0.355 1.387) (xy 0.285 1.426) (xy 0.21 1.456) (xy 0.205 1.458) (xy 0.131 1.477) (xy 0.054 1.487)
				(xy -0.025 1.489) (xy -0.103 1.482) (xy -0.178 1.466) (xy -0.206 1.458) (xy -0.281 1.428) (xy -0.351 1.39)
				(xy -0.416 1.344) (xy -0.474 1.29) (xy -0.526 1.23) (xy -0.571 1.164) (xy -0.607 1.093) (xy -0.63 1.034)
				(xy -0.649 0.96) (xy -0.659 0.883) (xy -0.661 0.804) (xy -0.654 0.726) (xy -0.638 0.651) (xy -0.63 0.623)
				(xy -0.618 0.591) (xy -0.602 0.554) (xy -0.584 0.518) (xy -0.566 0.485) (xy -0.553 0.463) (xy -0.509 0.407)
				(xy -0.457 0.352) (xy -0.397 0.299) (xy -0.33 0.25) (xy -0.289 0.224) (xy -0.273 0.212) (xy -0.263 0.2)
				(xy -0.262 0.197) (xy -0.263 0.19) (xy -0.268 0.175) (xy -0.277 0.151) (xy -0.288 0.121) (xy -0.302 0.084)
				(xy -0.319 0.042) (xy -0.338 -0.005) (xy -0.358 -0.056) (xy -0.381 -0.111) (xy -0.404 -0.168) (xy -0.428 -0.228)
				(xy -0.453 -0.288) (xy -0.478 -0.349) (xy -0.504 -0.41) (xy -0.529 -0.47) (xy -0.553 -0.527) (xy -0.576 -0.583)
				(xy -0.598 -0.635) (xy -0.619 -0.683) (xy -0.638 -0.727) (xy -0.655 -0.765) (xy -0.669 -0.797) (xy -0.68 -0.822)
				(xy -0.689 -0.839) (xy -0.694 -0.848) (xy -0.695 -0.849) (xy -0.699 -0.85) (xy -0.706 -0.849) (xy -0.717 -0.845)
				(xy -0.732 -0.839) (xy -0.752 -0.829) (xy -0.779 -0.815) (xy -0.814 -0.797) (xy -0.817 -0.795) (xy -0.848 -0.779)
				(xy -0.877 -0.764) (xy -0.902 -0.752) (xy -0.922 -0.743) (xy -0.936 -0.737) (xy -0.941 -0.736) (xy -0.949 -0.739)
				(xy -0.964 -0.748) (xy -0.987 -0.761) (xy -1.015 -0.78) (xy -1.05 -0.803) (xy -1.072 -0.818) (xy -1.138 -0.863)
				(xy -1.195 -0.903) (xy -1.245 -0.937) (xy -1.289 -0.966) (xy -1.325 -0.991) (xy -1.356 -1.012) (xy -1.381 -1.029)
				(xy -1.401 -1.042) (xy -1.416 -1.052) (xy -1.427 -1.059) (xy -1.435 -1.064) (xy -1.439 -1.066) (xy -1.44 -1.066)
				(xy -1.449 -1.064) (xy -1.453 -1.061) (xy -1.458 -1.057) (xy -1.47 -1.046) (xy -1.487 -1.029) (xy -1.509 -1.007)
				(xy -1.537 -0.98) (xy -1.568 -0.95) (xy -1.602 -0.915) (xy -1.639 -0.879) (xy -1.678 -0.84) (xy -1.678 -0.839)
				(xy -1.726 -0.792) (xy -1.767 -0.751) (xy -1.801 -0.716) (xy -1.829 -0.687) (xy -1.852 -0.663) (xy -1.869 -0.644)
				(xy -1.882 -0.63) (xy -1.89 -0.62) (xy -1.894 -0.613) (xy -1.895 -0.61) (xy -1.892 -0.603) (xy -1.884 -0.588)
				(xy -1.87 -0.565) (xy -1.85 -0.536) (xy -1.826 -0.499) (xy -1.797 -0.455) (xy -1.763 -0.405) (xy -1.73 -0.358)
				(xy -1.7 -0.313) (xy -1.671 -0.271) (xy -1.645 -0.232) (xy -1.621 -0.197) (xy -1.601 -0.166) (xy -1.584 -0.141)
				(xy -1.572 -0.121) (xy -1.565 -0.109) (xy -1.563 -0.105) (xy -1.563 -0.099) (xy -1.566 -0.087) (xy -1.572 -0.07)
				(xy -1.58 -0.045) (xy -1.592 -0.013) (xy -1.607 0.026) (xy -1.626 0.074) (xy -1.648 0.13) (xy -1.654 0.145)
				(xy -1.676 0.199) (xy -1.695 0.245) (xy -1.71 0.282) (xy -1.723 0.313) (xy -1.733 0.337) (xy -1.741 0.356)
				(xy -1.748 0.369) (xy -1.753 0.379) (xy -1.758 0.385) (xy -1.761 0.388) (xy -1.763 0.389) (xy -1.767 0.39)
				(xy -1.774 0.392) (xy -1.784 0.395) (xy -1.799 0.398) (xy -1.818 0.402) (xy -1.843 0.407) (xy -1.873 0.413)
				(xy -1.91 0.42) (xy -1.954 0.429) (xy -2.005 0.438) (xy -2.065 0.449) (xy -2.133 0.462) (xy -2.211 0.477)
				(xy -2.22 0.478) (xy -2.26 0.486) (xy -2.29 0.491) (xy -2.313 0.496) (xy -2.33 0.499) (xy -2.341 0.502)
				(xy -2.349 0.504) (xy -2.353 0.506) (xy -2.356 0.508) (xy -2.359 0.51) (xy -2.36 0.511) (xy -2.361 0.514)
				(xy -2.363 0.518) (xy -2.364 0.526) (xy -2.365 0.536) (xy -2.366 0.551) (xy -2.366 0.571) (xy -2.367 0.597)
				(xy -2.367 0.629) (xy -2.368 0.668) (xy -2.368 0.715) (xy -2.368 0.771) (xy -2.368 0.834) (xy -2.368 1.148)
				(xy -2.356 1.155) (xy -2.349 1.158) (xy -2.333 1.162) (xy -2.309 1.167) (xy -2.278 1.173) (xy -2.24 1.181)
				(xy -2.197 1.189) (xy -2.149 1.198) (xy -2.098 1.208) (xy -2.051 1.217) (xy -1.996 1.227) (xy -1.945 1.237)
				(xy -1.897 1.246) (xy -1.854 1.254) (xy -1.817 1.262) (xy -1.787 1.268) (xy -1.764 1.273) (xy -1.75 1.277)
				(xy -1.745 1.279) (xy -1.741 1.285) (xy -1.733 1.3) (xy -1.722 1.322) (xy -1.709 1.35) (xy -1.694 1.382)
				(xy -1.677 1.419) (xy -1.66 1.458) (xy -1.642 1.498) (xy -1.625 1.539) (xy -1.608 1.58) (xy -1.592 1.618)
				(xy -1.578 1.653) (xy -1.565 1.684) (xy -1.556 1.709) (xy -1.549 1.729) (xy -1.546 1.74) (xy -1.546 1.742)
				(xy -1.549 1.749) (xy -1.558 1.763) (xy -1.571 1.784) (xy -1.588 1.811) (xy -1.61 1.843) (xy -1.634 1.88)
				(xy -1.661 1.92) (xy -1.691 1.963) (xy -1.722 2.008) (xy -1.762 2.067) (xy -1.796 2.117) (xy -1.825 2.16)
				(xy -1.848 2.196) (xy -1.867 2.225) (xy -1.881 2.247) (xy -1.89 2.262) (xy -1.895 2.272) (xy -1.895 2.275)
				(xy -1.894 2.279) (xy -1.891 2.285) (xy -1.884 2.293) (xy -1.875 2.305) (xy -1.861 2.32) (xy -1.843 2.339)
				(xy -1.82 2.363) (xy -1.792 2.392) (xy -1.758 2.426) (xy -1.718 2.466) (xy -1.676 2.509) (xy -1.627 2.557)
				(xy -1.585 2.599) (xy -1.549 2.634) (xy -1.52 2.663) (xy -1.495 2.686) (xy -1.476 2.704) (xy -1.462 2.716)
				(xy -1.452 2.724) (xy -1.446 2.728) (xy -1.444 2.728) (xy -1.437 2.726) (xy -1.423 2.717) (xy -1.401 2.703)
				(xy -1.372 2.685) (xy -1.337 2.661) (xy -1.295 2.634) (xy -1.248 2.602) (xy -1.196 2.566) (xy -1.173 2.551)
				(xy -1.118 2.513) (xy -1.071 2.481) (xy -1.031 2.454) (xy -0.998 2.432) (xy -0.97 2.413) (xy -0.948 2.399)
				(xy -0.931 2.389) (xy -0.917 2.381) (xy -0.907 2.376) (xy -0.901 2.373) (xy -0.897 2.373) (xy -0.888 2.375)
				(xy -0.87 2.38) (xy -0.845 2.39) (xy -0.813 2.402) (xy -0.774 2.417) (xy -0.73 2.434) (xy -0.681 2.454)
				(xy -0.629 2.475) (xy -0.586 2.493) (xy -0.55 2.508) (xy -0.522 2.52) (xy -0.499 2.529) (xy -0.482 2.537)
				(xy -0.47 2.543) (xy -0.461 2.548) (xy -0.455 2.551) (xy -0.452 2.554) (xy -0.449 2.557) (xy -0.448 2.56)
				(xy -0.447 2.566) (xy -0.443 2.582) (xy -0.438 2.605) (xy -0.432 2.637) (xy -0.425 2.674) (xy -0.417 2.717)
				(xy -0.407 2.765) (xy -0.398 2.817) (xy -0.388 2.871) (xy -0.387 2.876) (xy -0.375 2.94) (xy -0.364 2.995)
				(xy -0.356 3.042) (xy -0.348 3.081) (xy -0.342 3.112) (xy -0.337 3.137) (xy -0.332 3.157) (xy -0.328 3.171)
				(xy -0.325 3.181) (xy -0.323 3.188) (xy -0.32 3.191) (xy -0.32 3.192) (xy -0.317 3.194) (xy -0.313 3.195)
				(xy -0.307 3.197) (xy -0.298 3.198) (xy -0.286 3.199) (xy -0.269 3.199) (xy -0.247 3.2) (xy -0.219 3.2)
				(xy -0.184 3.201) (xy -0.142 3.201) (xy -0.092 3.201) (xy -0.033 3.201) (xy -0.001 3.201) (xy 0.063 3.201)
			)
			(stroke
				(width 0.01)
				(type solid)
			)
			(fill yes)
			(layer "B.Mask")
		)
	)
	(footprint "antmicro-footprints:antmicro-logo"
		(layer "B.Cu")
		(at 144.260059 92.357277 180)
		(property "Reference" "N1"
			(at 0.05 5.5 0)
			(layer "B.SilkS")
			(hide yes)
			(effects
				(font
					(size 0.7 0.7)
					(thickness 0.15)
				)
				(justify left bottom mirror)
			)
		)
		(property "Value" "antmicro_logo"
			(at -0.101 -5.099 0)
			(layer "B.Fab")
			(hide yes)
			(effects
				(font
					(size 0.7 0.7)
					(thickness 0.15)
				)
				(justify left bottom mirror)
			)
		)
		(property "Description" "Mechanical part"
			(at 0 0 180)
			(layer "F.Fab")
			(hide yes)
			(effects
				(font
					(size 1.27 1.27)
					(thickness 0.15)
				)
			)
		)
		(property "Author" "Antmicro"
			(at 288.520118 184.714554 0)
			(layer "B.Fab")
			(hide yes)
			(effects
				(font
					(size 1 1)
					(thickness 0.15)
				)
				(justify mirror)
			)
		)
		(property "License" "Apache-2.0"
			(at 288.520118 184.714554 0)
			(layer "B.Fab")
			(hide yes)
			(effects
				(font
					(size 1 1)
					(thickness 0.15)
				)
				(justify mirror)
			)
		)
		(property "MPN" ""
			(at 288.520118 184.714554 0)
			(layer "B.Fab")
			(hide yes)
			(effects
				(font
					(size 1 1)
					(thickness 0.15)
				)
				(justify mirror)
			)
		)
		(property "Manufacturer" ""
			(at 288.520118 184.714554 0)
			(layer "B.Fab")
			(hide yes)
			(effects
				(font
					(size 1 1)
					(thickness 0.15)
				)
				(justify mirror)
			)
		)
		(property "Public" "False"
			(at 288.520118 184.714554 0)
			(layer "B.Fab")
			(hide yes)
			(effects
				(font
					(size 1 1)
					(thickness 0.15)
				)
				(justify mirror)
			)
		)
		(sheetname "/")
		(sheetfile "m2-pcie-adapter.kicad_sch")
		(attr exclude_from_pos_files allow_soldermask_bridges)
		(fp_poly
			(pts
				(xy 5.212 -0.944) (xy 4.834 -0.944) (xy 4.834 1.292) (xy 5.212 1.292) (xy 5.212 -0.944)
			)
			(stroke
				(width 0.00186)
				(type solid)
			)
			(fill yes)
			(layer "B.Cu")
		)
		(fp_poly
			(pts
				(xy 8.164 1.321) (xy 8.193 1.317) (xy 8.204 1.31) (xy 8.204 1.308) (xy 8.2 1.285) (xy 8.188 1.24)
				(xy 8.171 1.181) (xy 8.163 1.156) (xy 8.142 1.092) (xy 8.126 1.053) (xy 8.112 1.034) (xy 8.097 1.031)
				(xy 8.094 1.032) (xy 7.996 1.053) (xy 7.886 1.06) (xy 7.778 1.053) (xy 7.683 1.032) (xy 7.665 1.026)
				(xy 7.622 1.009) (xy 7.622 -0.944) (xy 7.244 -0.944) (xy 7.244 1.178) (xy 7.358 1.219) (xy 7.457 1.253)
				(xy 7.548 1.277) (xy 7.639 1.295) (xy 7.738 1.307) (xy 7.856 1.315) (xy 7.94 1.319) (xy 8.042 1.322)
				(xy 8.115 1.322) (xy 8.164 1.321)
			)
			(stroke
				(width 0.00186)
				(type solid)
			)
			(fill yes)
			(layer "B.Cu")
		)
		(fp_poly
			(pts
				(xy 0.795 1.891) (xy 0.798 1.849) (xy 0.8 1.786) (xy 0.802 1.705) (xy 0.803 1.612) (xy 0.803 1.599)
				(xy 0.803 1.292) (xy 1.181 1.292) (xy 1.181 1.04) (xy 0.803 1.04) (xy 0.803 -0.498) (xy 0.838 -0.566)
				(xy 0.885 -0.631) (xy 0.944 -0.671) (xy 1.021 -0.688) (xy 1.082 -0.689) (xy 1.181 -0.685) (xy 1.181 -0.806)
				(xy 1.178 -0.88) (xy 1.17 -0.926) (xy 1.161 -0.939) (xy 1.138 -0.945) (xy 1.09 -0.95) (xy 1.028 -0.954)
				(xy 0.984 -0.956) (xy 0.897 -0.957) (xy 0.832 -0.953) (xy 0.778 -0.942) (xy 0.743 -0.931) (xy 0.647 -0.886)
				(xy 0.571 -0.823) (xy 0.508 -0.737) (xy 0.488 -0.701) (xy 0.433 -0.593) (xy 0.428 0.223) (xy 0.424 1.04)
				(xy 0.173 1.04) (xy 0.173 1.292) (xy 0.425 1.292) (xy 0.425 1.795) (xy 0.603 1.85) (xy 0.673 1.872)
				(xy 0.733 1.89) (xy 0.774 1.902) (xy 0.792 1.906) (xy 0.795 1.891)
			)
			(stroke
				(width 0.00186)
				(type solid)
			)
			(fill yes)
			(layer "B.Cu")
		)
		(fp_poly
			(pts
				(xy -0.82 1.315) (xy -0.737 1.312) (xy -0.672 1.308) (xy -0.621 1.301) (xy -0.577 1.291) (xy -0.56 1.286)
				(xy -0.417 1.232) (xy -0.302 1.164) (xy -0.212 1.082) (xy -0.154 0.996) (xy -0.135 0.961) (xy -0.119 0.927)
				(xy -0.105 0.893) (xy -0.094 0.855) (xy -0.085 0.811) (xy -0.078 0.758) (xy -0.073 0.693) (xy -0.069 0.612)
				(xy -0.067 0.515) (xy -0.065 0.397) (xy -0.064 0.256) (xy -0.064 0.088) (xy -0.063 -0.105) (xy -0.063 -0.944)
				(xy -0.441 -0.944) (xy -0.441 -0.113) (xy -0.442 0.083) (xy -0.442 0.25) (xy -0.443 0.391) (xy -0.445 0.508)
				(xy -0.448 0.604) (xy -0.452 0.682) (xy -0.457 0.744) (xy -0.465 0.794) (xy -0.474 0.833) (xy -0.486 0.864)
				(xy -0.501 0.89) (xy -0.518 0.913) (xy -0.538 0.937) (xy -0.539 0.939) (xy -0.604 0.997) (xy -0.684 1.039)
				(xy -0.784 1.066) (xy -0.822 1.072) (xy -0.927 1.078) (xy -1.044 1.073) (xy -1.158 1.056) (xy -1.24 1.034)
				(xy -1.3 1.013) (xy -1.304 0.034) (xy -1.308 -0.944) (xy -1.686 -0.944) (xy -1.686 1.178) (xy -1.54 1.225)
				(xy -1.44 1.257) (xy -1.354 1.28) (xy -1.276 1.297) (xy -1.195 1.307) (xy -1.105 1.313) (xy -0.995 1.315)
				(xy -0.93 1.315) (xy -0.82 1.315)
			)
			(stroke
				(width 0.00186)
				(type solid)
			)
			(fill yes)
			(layer "B.Cu")
		)
		(fp_poly
			(pts
				(xy 3.757 1.312) (xy 3.91 1.278) (xy 4.043 1.223) (xy 4.153 1.146) (xy 4.24 1.047) (xy 4.282 0.977)
				(xy 4.299 0.943) (xy 4.313 0.91) (xy 4.325 0.876) (xy 4.335 0.837) (xy 4.343 0.791) (xy 4.349 0.734)
				(xy 4.353 0.665) (xy 4.357 0.581) (xy 4.359 0.478) (xy 4.361 0.354) (xy 4.361 0.206) (xy 4.362 0.031)
				(xy 4.362 -0.111) (xy 4.362 -0.944) (xy 3.985 -0.944) (xy 3.98 -0.074) (xy 3.976 0.796) (xy 3.93 0.879)
				(xy 3.867 0.961) (xy 3.786 1.022) (xy 3.691 1.062) (xy 3.586 1.079) (xy 3.476 1.074) (xy 3.366 1.045)
				(xy 3.26 0.994) (xy 3.185 0.938) (xy 3.118 0.88) (xy 3.118 -0.944) (xy 2.74 -0.944) (xy 2.74 -0.092)
				(xy 2.739 0.122) (xy 2.739 0.305) (xy 2.737 0.459) (xy 2.735 0.585) (xy 2.732 0.683) (xy 2.729 0.755)
				(xy 2.725 0.802) (xy 2.722 0.821) (xy 2.679 0.91) (xy 2.613 0.981) (xy 2.523 1.034) (xy 2.413 1.067)
				(xy 2.284 1.079) (xy 2.154 1.073) (xy 2.082 1.064) (xy 2.031 1.056) (xy 1.989 1.046) (xy 1.944 1.031)
				(xy 1.917 1.021) (xy 1.874 1.005) (xy 1.874 -0.944) (xy 1.511 -0.944) (xy 1.511 1.18) (xy 1.661 1.228)
				(xy 1.83 1.276) (xy 1.988 1.306) (xy 2.148 1.319) (xy 2.314 1.319) (xy 2.448 1.311) (xy 2.557 1.297)
				(xy 2.649 1.272) (xy 2.732 1.237) (xy 2.811 1.189) (xy 2.843 1.165) (xy 2.947 1.087) (xy 3.012 1.14)
				(xy 3.14 1.224) (xy 3.283 1.283) (xy 3.443 1.315) (xy 3.582 1.323) (xy 3.757 1.312)
			)
			(stroke
				(width 0.00186)
				(type solid)
			)
			(fill yes)
			(layer "B.Cu")
		)
		(fp_poly
			(pts
				(xy 9.278 1.313) (xy 9.419 1.281) (xy 9.543 1.225) (xy 9.656 1.146) (xy 9.708 1.097) (xy 9.808 0.975)
				(xy 9.887 0.831) (xy 9.945 0.666) (xy 9.984 0.476) (xy 9.998 0.354) (xy 10.005 0.134) (xy 9.992 -0.072)
				(xy 9.96 -0.262) (xy 9.908 -0.434) (xy 9.837 -0.585) (xy 9.749 -0.714) (xy 9.643 -0.819) (xy 9.578 -0.867)
				(xy 9.475 -0.918) (xy 9.352 -0.956) (xy 9.219 -0.98) (xy 9.087 -0.986) (xy 8.966 -0.975) (xy 8.81 -0.933)
				(xy 8.673 -0.864) (xy 8.553 -0.771) (xy 8.452 -0.653) (xy 8.371 -0.511) (xy 8.31 -0.346) (xy 8.277 -0.202)
				(xy 8.249 0.011) (xy 8.243 0.182) (xy 8.619 0.182) (xy 8.626 0.007) (xy 8.647 -0.163) (xy 8.682 -0.318)
				(xy 8.73 -0.449) (xy 8.792 -0.552) (xy 8.87 -0.633) (xy 8.961 -0.69) (xy 9.06 -0.721) (xy 9.164 -0.724)
				(xy 9.268 -0.699) (xy 9.303 -0.683) (xy 9.391 -0.625) (xy 9.465 -0.546) (xy 9.524 -0.443) (xy 9.569 -0.315)
				(xy 9.601 -0.162) (xy 9.62 0) (xy 9.628 0.198) (xy 9.62 0.382) (xy 9.597 0.55) (xy 9.558 0.698)
				(xy 9.505 0.825) (xy 9.439 0.927) (xy 9.397 0.971) (xy 9.307 1.035) (xy 9.21 1.071) (xy 9.109 1.079)
				(xy 9.009 1.062) (xy 8.915 1.019) (xy 8.831 0.953) (xy 8.76 0.863) (xy 8.733 0.813) (xy 8.684 0.68)
				(xy 8.648 0.526) (xy 8.627 0.358) (xy 8.619 0.182) (xy 8.243 0.182) (xy 8.242 0.218) (xy 8.255 0.417)
				(xy 8.288 0.602) (xy 8.339 0.772) (xy 8.41 0.923) (xy 8.498 1.051) (xy 8.524 1.081) (xy 8.637 1.182)
				(xy 8.765 1.255) (xy 8.908 1.302) (xy 9.068 1.322) (xy 9.117 1.323) (xy 9.278 1.313)
			)
			(stroke
				(width 0.00186)
				(type solid)
			)
			(fill yes)
			(layer "B.Cu")
		)
		(fp_poly
			(pts
				(xy 6.48 1.32) (xy 6.584 1.31) (xy 6.642 1.3) (xy 6.701 1.282) (xy 6.765 1.259) (xy 6.825 1.233)
				(xy 6.873 1.209) (xy 6.9 1.189) (xy 6.902 1.186) (xy 6.901 1.166) (xy 6.889 1.128) (xy 6.872 1.079)
				(xy 6.852 1.03) (xy 6.833 0.989) (xy 6.818 0.966) (xy 6.815 0.963) (xy 6.795 0.969) (xy 6.757 0.985)
				(xy 6.717 1.002) (xy 6.597 1.044) (xy 6.478 1.06) (xy 6.365 1.05) (xy 6.267 1.016) (xy 6.184 0.957)
				(xy 6.109 0.87) (xy 6.042 0.76) (xy 5.988 0.629) (xy 5.964 0.554) (xy 5.946 0.461) (xy 5.934 0.347)
				(xy 5.929 0.22) (xy 5.931 0.091) (xy 5.938 -0.032) (xy 5.953 -0.138) (xy 5.965 -0.191) (xy 6.018 -0.347)
				(xy 6.085 -0.476) (xy 6.166 -0.576) (xy 6.262 -0.649) (xy 6.269 -0.653) (xy 6.318 -0.678) (xy 6.36 -0.692)
				(xy 6.409 -0.698) (xy 6.476 -0.7) (xy 6.48 -0.7) (xy 6.551 -0.697) (xy 6.613 -0.686) (xy 6.676 -0.665)
				(xy 6.75 -0.631) (xy 6.805 -0.602) (xy 6.811 -0.606) (xy 6.823 -0.627) (xy 6.842 -0.667) (xy 6.868 -0.73)
				(xy 6.904 -0.819) (xy 6.907 -0.827) (xy 6.898 -0.844) (xy 6.866 -0.868) (xy 6.818 -0.895) (xy 6.759 -0.922)
				(xy 6.697 -0.945) (xy 6.68 -0.95) (xy 6.596 -0.968) (xy 6.494 -0.98) (xy 6.388 -0.984) (xy 6.292 -0.98)
				(xy 6.251 -0.975) (xy 6.192 -0.96) (xy 6.121 -0.935) (xy 6.055 -0.906) (xy 5.924 -0.825) (xy 5.811 -0.718)
				(xy 5.717 -0.586) (xy 5.641 -0.431) (xy 5.585 -0.252) (xy 5.566 -0.164) (xy 5.552 -0.061) (xy 5.545 0.061)
				(xy 5.544 0.193) (xy 5.549 0.327) (xy 5.56 0.453) (xy 5.576 0.563) (xy 5.589 0.623) (xy 5.65 0.797)
				(xy 5.731 0.949) (xy 5.831 1.077) (xy 5.948 1.181) (xy 6.081 1.259) (xy 6.187 1.298) (xy 6.27 1.314)
				(xy 6.372 1.322) (xy 6.48 1.32)
			)
			(stroke
				(width 0.00186)
				(type solid)
			)
			(fill yes)
			(layer "B.Cu")
		)
		(fp_poly
			(pts
				(xy -2.763 1.313) (xy -2.663 1.294) (xy -2.55 1.259) (xy -2.459 1.216) (xy -2.38 1.16) (xy -2.341 1.124)
				(xy -2.284 1.053) (xy -2.232 0.961) (xy -2.192 0.861) (xy -2.174 0.79) (xy -2.17 0.754) (xy -2.167 0.69)
				(xy -2.164 0.599) (xy -2.162 0.485) (xy -2.16 0.35) (xy -2.159 0.196) (xy -2.158 0.027) (xy -2.158 -0.064)
				(xy -2.158 -0.833) (xy -2.232 -0.865) (xy -2.364 -0.913) (xy -2.517 -0.949) (xy -2.682 -0.974) (xy -2.85 -0.986)
				(xy -3.011 -0.983) (xy -3.097 -0.975) (xy -3.264 -0.942) (xy -3.407 -0.889) (xy -3.525 -0.817) (xy -3.618 -0.725)
				(xy -3.686 -0.616) (xy -3.729 -0.487) (xy -3.746 -0.341) (xy -3.746 -0.268) (xy -3.744 -0.254) (xy -3.383 -0.254)
				(xy -3.38 -0.384) (xy -3.352 -0.497) (xy -3.298 -0.591) (xy -3.221 -0.665) (xy -3.12 -0.719) (xy -3.072 -0.735)
				(xy -3.011 -0.745) (xy -2.928 -0.75) (xy -2.835 -0.75) (xy -2.74 -0.744) (xy -2.655 -0.734) (xy -2.589 -0.72)
				(xy -2.579 -0.716) (xy -2.504 -0.689) (xy -2.504 0.302) (xy -2.595 0.291) (xy -2.653 0.282) (xy -2.728 0.267)
				(xy -2.806 0.25) (xy -2.831 0.244) (xy -2.992 0.194) (xy -3.125 0.133) (xy -3.229 0.06) (xy -3.306 -0.026)
				(xy -3.357 -0.125) (xy -3.381 -0.238) (xy -3.383 -0.254) (xy -3.744 -0.254) (xy -3.725 -0.126) (xy -3.678 0)
				(xy -3.602 0.112) (xy -3.559 0.158) (xy -3.465 0.233) (xy -3.343 0.303) (xy -3.198 0.365) (xy -3.034 0.417)
				(xy -2.856 0.46) (xy -2.666 0.49) (xy -2.663 0.49) (xy -2.5 0.51) (xy -2.51 0.644) (xy -2.528 0.77)
				(xy -2.564 0.871) (xy -2.62 0.949) (xy -2.697 1.007) (xy -2.797 1.045) (xy -2.845 1.056) (xy -2.975 1.067)
				(xy -3.12 1.056) (xy -3.272 1.024) (xy -3.426 0.972) (xy -3.439 0.967) (xy -3.488 0.947) (xy -3.523 0.936)
				(xy -3.537 0.934) (xy -3.545 0.95) (xy -3.56 0.987) (xy -3.579 1.035) (xy -3.598 1.086) (xy -3.613 1.129)
				(xy -3.622 1.155) (xy -3.623 1.159) (xy -3.609 1.169) (xy -3.575 1.188) (xy -3.537 1.206) (xy -3.395 1.257)
				(xy -3.239 1.294) (xy -3.075 1.316) (xy -2.914 1.323) (xy -2.763 1.313)
			)
			(stroke
				(width 0.00186)
				(type solid)
			)
			(fill yes)
			(layer "B.Cu")
		)
		(fp_poly
			(pts
				(xy -7.153 3.366) (xy -7.087 3.351) (xy -7.086 3.351) (xy -7.066 3.34) (xy -7.021 3.315) (xy -6.953 3.277)
				(xy -6.865 3.227) (xy -6.759 3.167) (xy -6.639 3.099) (xy -6.505 3.022) (xy -6.361 2.94) (xy -6.209 2.853)
				(xy -6.052 2.762) (xy -5.891 2.67) (xy -5.729 2.577) (xy -5.569 2.485) (xy -5.413 2.395) (xy -5.264 2.309)
				(xy -5.123 2.227) (xy -4.994 2.152) (xy -4.878 2.085) (xy -4.778 2.027) (xy -4.697 1.979) (xy -4.636 1.943)
				(xy -4.599 1.921) (xy -4.595 1.918) (xy -4.528 1.863) (xy -4.476 1.798) (xy -4.434 1.725) (xy -4.429 0.224)
				(xy -4.429 -0.063) (xy -4.428 -0.323) (xy -4.429 -0.553) (xy -4.429 -0.755) (xy -4.43 -0.928) (xy -4.432 -1.071)
				(xy -4.434 -1.184) (xy -4.436 -1.266) (xy -4.439 -1.318) (xy -4.441 -1.337) (xy -4.448 -1.36) (xy -4.454 -1.382)
				(xy -4.463 -1.403) (xy -4.476 -1.423) (xy -4.494 -1.445) (xy -4.519 -1.47) (xy -4.552 -1.497) (xy -4.596 -1.529)
				(xy -4.652 -1.567) (xy -4.721 -1.611) (xy -4.805 -1.663) (xy -4.906 -1.723) (xy -5.025 -1.794) (xy -5.165 -1.875)
				(xy -5.326 -1.969) (xy -5.511 -2.076) (xy -5.72 -2.197) (xy -5.813 -2.251) (xy -7.079 -2.982) (xy -7.197 -2.988)
				(xy -7.315 -2.994) (xy -7.78 -2.727) (xy -8.064 -2.563) (xy -8.323 -2.415) (xy -8.557 -2.28) (xy -8.767 -2.159)
				(xy -8.955 -2.051) (xy -9.122 -1.954) (xy -9.27 -1.868) (xy -9.399 -1.792) (xy -9.51 -1.726) (xy -9.606 -1.669)
				(xy -9.688 -1.619) (xy -9.756 -1.576) (xy -9.812 -1.539) (xy -9.857 -1.507) (xy -9.893 -1.481) (xy -9.92 -1.458)
				(xy -9.94 -1.437) (xy -9.955 -1.42) (xy -9.965 -1.403) (xy -9.972 -1.387) (xy -9.977 -1.371) (xy -9.981 -1.354)
				(xy -9.985 -1.337) (xy -9.988 -1.309) (xy -9.991 -1.25) (xy -9.993 -1.161) (xy -9.995 -1.041) (xy -9.996 -0.891)
				(xy -9.997 -0.712) (xy -9.998 -0.503) (xy -9.998 -0.266) (xy -9.997 0) (xy -9.997 0.189) (xy -9.024 0.189)
				(xy -9.024 -0.015) (xy -9.024 -0.191) (xy -9.023 -0.34) (xy -9.022 -0.464) (xy -9.021 -0.567) (xy -9.018 -0.65)
				(xy -9.014 -0.717) (xy -9.01 -0.768) (xy -9.003 -0.808) (xy -8.995 -0.837) (xy -8.986 -0.859) (xy -8.974 -0.876)
				(xy -8.961 -0.891) (xy -8.945 -0.905) (xy -8.943 -0.906) (xy -8.922 -0.921) (xy -8.877 -0.949) (xy -8.81 -0.989)
				(xy -8.725 -1.039) (xy -8.625 -1.098) (xy -8.512 -1.164) (xy -8.389 -1.235) (xy -8.26 -1.31) (xy -8.128 -1.386)
				(xy -7.995 -1.463) (xy -7.864 -1.538) (xy -7.739 -1.609) (xy -7.622 -1.676) (xy -7.517 -1.735) (xy -7.425 -1.787)
				(xy -7.351 -1.828) (xy -7.297 -1.857) (xy -7.266 -1.872) (xy -7.261 -1.874) (xy -7.222 -1.885) (xy -7.195 -1.886)
				(xy -7.163 -1.875) (xy -7.144 -1.867) (xy -7.117 -1.854) (xy -7.067 -1.827) (xy -6.997 -1.788) (xy -6.909 -1.738)
				(xy -6.805 -1.679) (xy -6.691 -1.614) (xy -6.567 -1.543) (xy -6.438 -1.469) (xy -6.306 -1.392) (xy -6.174 -1.316)
				(xy -6.045 -1.241) (xy -5.922 -1.17) (xy -5.809 -1.103) (xy -5.708 -1.044) (xy -5.622 -0.992) (xy -5.553 -0.952)
				(xy -5.507 -0.923) (xy -5.484 -0.907) (xy -5.483 -0.907) (xy -5.467 -0.892) (xy -5.453 -0.878) (xy -5.441 -0.861)
				(xy -5.431 -0.839) (xy -5.423 -0.81) (xy -5.417 -0.772) (xy -5.412 -0.721) (xy -5.408 -0.656) (xy -5.406 -0.574)
				(xy -5.404 -0.473) (xy -5.403 -0.35) (xy -5.402 -0.203) (xy -5.402 -0.03) (xy -5.402 0.172) (xy -5.402 0.189)
				(xy -5.402 0.395) (xy -5.402 0.572) (xy -5.403 0.721) (xy -5.404 0.847) (xy -5.406 0.95) (xy -5.408 1.034)
				(xy -5.412 1.101) (xy -5.418 1.153) (xy -5.425 1.193) (xy -5.434 1.223) (xy -5.445 1.245) (xy -5.458 1.262)
				(xy -5.473 1.276) (xy -5.491 1.29) (xy -5.499 1.295) (xy -5.522 1.31) (xy -5.57 1.339) (xy -5.64 1.381)
				(xy -5.729 1.433) (xy -5.835 1.496) (xy -5.956 1.566) (xy -6.088 1.643) (xy -6.229 1.725) (xy -6.348 1.793)
				(xy -6.519 1.891) (xy -6.664 1.974) (xy -6.786 2.044) (xy -6.888 2.101) (xy -6.971 2.147) (xy -7.038 2.183)
				(xy -7.091 2.21) (xy -7.132 2.229) (xy -7.163 2.242) (xy -7.187 2.249) (xy -7.205 2.252) (xy -7.211 2.252)
				(xy -7.228 2.251) (xy -7.249 2.246) (xy -7.276 2.236) (xy -7.312 2.219) (xy -7.359 2.196) (xy -7.419 2.165)
				(xy -7.495 2.123) (xy -7.587 2.072) (xy -7.699 2.008) (xy -7.832 1.932) (xy -7.99 1.842) (xy -8.1 1.778)
				(xy -8.248 1.693) (xy -8.388 1.611) (xy -8.519 1.535) (xy -8.637 1.466) (xy -8.739 1.406) (xy -8.825 1.355)
				(xy -8.89 1.316) (xy -8.933 1.29) (xy -8.951 1.278) (xy -8.966 1.265) (xy -8.978 1.251) (xy -8.989 1.234)
				(xy -8.998 1.212) (xy -9.005 1.182) (xy -9.011 1.141) (xy -9.015 1.087) (xy -9.018 1.019) (xy -9.021 0.933)
				(xy -9.022 0.827) (xy -9.023 0.699) (xy -9.024 0.546) (xy -9.024 0.366) (xy -9.024 0.189) (xy -9.997 0.189)
				(xy -9.997 0.224) (xy -9.996 0.479) (xy -9.996 0.705) (xy -9.995 0.903) (xy -9.994 1.075) (xy -9.993 1.223)
				(xy -9.992 1.35) (xy -9.99 1.456) (xy -9.987 1.545) (xy -9.984 1.617) (xy -9.98 1.675) (xy -9.974 1.721)
				(xy -9.968 1.757) (xy -9.961 1.784) (xy -9.952 1.805) (xy -9.941 1.821) (xy -9.929 1.834) (xy -9.915 1.847)
				(xy -9.9 1.86) (xy -9.893 1.866) (xy -9.873 1.88) (xy -9.828 1.909) (xy -9.759 1.951) (xy -9.669 2.005)
				(xy -9.56 2.07) (xy -9.433 2.145) (xy -9.291 2.228) (xy -9.136 2.319) (xy -8.969 2.416) (xy -8.793 2.518)
				(xy -8.61 2.624) (xy -8.59 2.635) (xy -8.377 2.759) (xy -8.189 2.867) (xy -8.024 2.962) (xy -7.882 3.044)
				(xy -7.759 3.114) (xy -7.656 3.173) (xy -7.568 3.221) (xy -7.496 3.261) (xy -7.437 3.293) (xy -7.389 3.317)
				(xy -7.351 3.336) (xy -7.321 3.349) (xy -7.296 3.357) (xy -7.276 3.363) (xy -7.259 3.366) (xy -7.242 3.367)
				(xy -7.237 3.368) (xy -7.153 3.366)
			)
			(stroke
				(width 0.00186)
				(type solid)
			)
			(fill yes)
			(layer "B.Cu")
		)
		(fp_poly
			(pts
				(xy -7.128 1.48) (xy -7.114 1.475) (xy -7.042 1.428) (xy -6.989 1.361) (xy -6.96 1.281) (xy -6.957 1.196)
				(xy -6.961 1.175) (xy -6.992 1.094) (xy -7.046 1.034) (xy -7.101 1.001) (xy -7.166 0.969) (xy -7.166 0.599)
				(xy -6.891 0.599) (xy -6.778 0.711) (xy -6.665 0.824) (xy -6.673 0.905) (xy -6.673 0.906) (xy -6.566 0.906)
				(xy -6.549 0.87) (xy -6.512 0.853) (xy -6.467 0.856) (xy -6.435 0.876) (xy -6.412 0.913) (xy -6.42 0.95)
				(xy -6.441 0.977) (xy -6.471 1.002) (xy -6.496 1.005) (xy -6.53 0.986) (xy -6.532 0.984) (xy -6.56 0.949)
				(xy -6.566 0.906) (xy -6.673 0.906) (xy -6.676 0.957) (xy -6.669 0.992) (xy -6.648 1.025) (xy -6.639 1.036)
				(xy -6.582 1.084) (xy -6.519 1.106) (xy -6.456 1.105) (xy -6.397 1.084) (xy -6.349 1.044) (xy -6.316 0.99)
				(xy -6.304 0.925) (xy -6.315 0.859) (xy -6.351 0.797) (xy -6.408 0.757) (xy -6.484 0.741) (xy -6.497 0.741)
				(xy -6.529 0.74) (xy -6.557 0.734) (xy -6.585 0.719) (xy -6.619 0.693) (xy -6.667 0.651) (xy -6.705 0.615)
				(xy -6.84 0.489) (xy -7.166 0.489) (xy -7.166 0.237) (xy -6.568 0.237) (xy -6.545 0.282) (xy -6.502 0.333)
				(xy -6.443 0.364) (xy -6.377 0.373) (xy -6.311 0.36) (xy -6.255 0.322) (xy -6.249 0.317) (xy -6.209 0.253)
				(xy -6.195 0.188) (xy -6.205 0.126) (xy -6.234 0.072) (xy -6.28 0.03) (xy -6.337 0.006) (xy -6.402 0.002)
				(xy -6.472 0.025) (xy -6.486 0.033) (xy -6.523 0.061) (xy -6.545 0.091) (xy -6.547 0.096) (xy -6.552 0.106)
				(xy -6.561 0.114) (xy -6.58 0.12) (xy -6.613 0.123) (xy -6.664 0.125) (xy -6.737 0.126) (xy -6.836 0.126)
				(xy -6.861 0.126) (xy -7.166 0.126) (xy -7.166 -0.11) (xy -6.842 -0.11) (xy -6.581 -0.373) (xy -6.507 -0.366)
				(xy -6.428 -0.372) (xy -6.367 -0.402) (xy -6.325 -0.457) (xy -6.314 -0.486) (xy -6.304 -0.561) (xy -6.322 -0.626)
				(xy -6.361 -0.678) (xy -6.422 -0.72) (xy -6.487 -0.736) (xy -6.55 -0.727) (xy -6.605 -0.697) (xy -6.648 -0.648)
				(xy -6.671 -0.583) (xy -6.672 -0.536) (xy -6.564 -0.536) (xy -6.559 -0.575) (xy -6.544 -0.597) (xy -6.508 -0.625)
				(xy -6.474 -0.623) (xy -6.441 -0.598) (xy -6.414 -0.56) (xy -6.417 -0.525) (xy -6.44 -0.497) (xy -6.48 -0.476)
				(xy -6.518 -0.48) (xy -6.549 -0.502) (xy -6.564 -0.536) (xy -6.672 -0.536) (xy -6.673 -0.52) (xy -6.664 -0.445)
				(xy -6.891 -0.22) (xy -7.166 -0.22) (xy -7.166 -0.593) (xy -7.101 -0.622) (xy -7.033 -0.668) (xy -6.986 -0.732)
				(xy -6.96 -0.805) (xy -6.956 -0.883) (xy -6.973 -0.959) (xy -7.013 -1.026) (xy -7.074 -1.079) (xy -7.088 -1.087)
				(xy -7.171 -1.112) (xy -7.258 -1.112) (xy -7.34 -1.087) (xy -7.341 -1.086) (xy -7.406 -1.036) (xy -7.448 -0.97)
				(xy -7.469 -0.895) (xy -7.468 -0.858) (xy -7.361 -0.858) (xy -7.355 -0.905) (xy -7.331 -0.942) (xy -7.31 -0.962)
				(xy -7.252 -0.999) (xy -7.195 -1.005) (xy -7.137 -0.979) (xy -7.116 -0.962) (xy -7.08 -0.923) (xy -7.066 -0.883)
				(xy -7.065 -0.858) (xy -7.079 -0.801) (xy -7.116 -0.751) (xy -7.167 -0.718) (xy -7.213 -0.708) (xy -7.27 -0.722)
				(xy -7.319 -0.76) (xy -7.352 -0.812) (xy -7.361 -0.858) (xy -7.468 -0.858) (xy -7.468 -0.817) (xy -7.445 -0.742)
				(xy -7.401 -0.677) (xy -7.336 -0.628) (xy -7.325 -0.622) (xy -7.26 -0.593) (xy -7.26 -0.22) (xy -7.535 -0.22)
				(xy -7.762 -0.445) (xy -7.753 -0.52) (xy -7.757 -0.595) (xy -7.785 -0.658) (xy -7.83 -0.703) (xy -7.887 -0.73)
				(xy -7.951 -0.735) (xy -8.015 -0.715) (xy -8.065 -0.678) (xy -8.109 -0.617) (xy -8.123 -0.551) (xy -8.12 -0.532)
				(xy -8.012 -0.532) (xy -8.009 -0.566) (xy -7.985 -0.598) (xy -7.946 -0.625) (xy -7.912 -0.623) (xy -7.883 -0.599)
				(xy -7.863 -0.558) (xy -7.868 -0.517) (xy -7.896 -0.486) (xy -7.915 -0.478) (xy -7.961 -0.48) (xy -7.985 -0.496)
				(xy -8.012 -0.532) (xy -8.12 -0.532) (xy -8.112 -0.486) (xy -8.079 -0.422) (xy -8.025 -0.381) (xy -7.953 -0.365)
				(xy -7.919 -0.366) (xy -7.845 -0.373) (xy -7.584 -0.11) (xy -7.26 -0.11) (xy -7.26 0.126) (xy -7.566 0.126)
				(xy -7.672 0.126) (xy -7.75 0.126) (xy -7.805 0.124) (xy -7.841 0.121) (xy -7.863 0.116) (xy -7.875 0.108)
				(xy -7.881 0.098) (xy -7.883 0.094) (xy -7.908 0.058) (xy -7.954 0.026) (xy -8.009 0.005) (xy -8.045 0.001)
				(xy -8.117 0.014) (xy -8.174 0.049) (xy -8.213 0.102) (xy -8.23 0.164) (xy -8.228 0.186) (xy -8.124 0.186)
				(xy -8.12 0.163) (xy -8.104 0.143) (xy -8.063 0.115) (xy -8.021 0.117) (xy -7.994 0.135) (xy -7.971 0.176)
				(xy -7.976 0.202) (xy -6.455 0.202) (xy -6.449 0.158) (xy -6.432 0.135) (xy -6.392 0.113) (xy -6.35 0.121)
				(xy -6.322 0.143) (xy -6.303 0.169) (xy -6.304 0.193) (xy -6.316 0.218) (xy -6.35 0.254) (xy -6.39 0.265)
				(xy -6.429 0.247) (xy -6.432 0.244) (xy -6.455 0.202) (xy -7.976 0.202) (xy -7.979 0.218) (xy -7.999 0.244)
				(xy -8.04 0.265) (xy -8.078 0.255) (xy -8.11 0.218) (xy -8.124 0.186) (xy -8.228 0.186) (xy -8.224 0.232)
				(xy -8.192 0.297) (xy -8.177 0.317) (xy -8.121 0.358) (xy -8.055 0.374) (xy -7.988 0.365) (xy -7.927 0.333)
				(xy -7.885 0.284) (xy -7.857 0.237) (xy -7.26 0.237) (xy -7.26 0.489) (xy -7.586 0.489) (xy -7.721 0.615)
				(xy -7.779 0.669) (xy -7.821 0.704) (xy -7.852 0.726) (xy -7.879 0.737) (xy -7.908 0.74) (xy -7.934 0.741)
				(xy -8.011 0.752) (xy -8.068 0.787) (xy -8.105 0.846) (xy -8.112 0.866) (xy -8.119 0.923) (xy -8.016 0.923)
				(xy -8.003 0.887) (xy -7.969 0.862) (xy -7.928 0.852) (xy -7.888 0.861) (xy -7.878 0.87) (xy -7.86 0.907)
				(xy -7.866 0.949) (xy -7.894 0.984) (xy -7.924 1.002) (xy -7.941 1.008) (xy -7.964 0.997) (xy -7.991 0.969)
				(xy -8.011 0.939) (xy -8.016 0.923) (xy -8.119 0.923) (xy -8.121 0.94) (xy -8.105 1.004) (xy -8.069 1.055)
				(xy -8.018 1.091) (xy -7.958 1.108) (xy -7.894 1.104) (xy -7.831 1.076) (xy -7.787 1.036) (xy -7.762 1.001)
				(xy -7.751 0.968) (xy -7.751 0.923) (xy -7.753 0.905) (xy -7.762 0.824) (xy -7.648 0.711) (xy -7.535 0.599)
				(xy -7.26 0.599) (xy -7.26 0.971) (xy -7.323 0.998) (xy -7.396 1.046) (xy -7.446 1.114) (xy -7.465 1.166)
				(xy -7.472 1.24) (xy -7.365 1.24) (xy -7.359 1.204) (xy -7.347 1.177) (xy -7.307 1.123) (xy -7.254 1.093)
				(xy -7.194 1.09) (xy -7.134 1.116) (xy -7.127 1.121) (xy -7.081 1.171) (xy -7.065 1.225) (xy -7.078 1.283)
				(xy -7.116 1.342) (xy -7.166 1.375) (xy -7.222 1.384) (xy -7.278 1.368) (xy -7.326 1.326) (xy -7.354 1.278)
				(xy -7.365 1.24) (xy -7.472 1.24) (xy -7.474 1.25) (xy -7.455 1.328) (xy -7.416 1.396) (xy -7.358 1.449)
				(xy -7.288 1.484) (xy -7.21 1.495) (xy -7.128 1.48)
			)
			(stroke
				(width 0.00186)
				(type solid)
			)
			(fill yes)
			(layer "B.Cu")
		)
		(fp_poly
			(pts
				(xy 5.212 -0.944) (xy 4.834 -0.944) (xy 4.834 1.292) (xy 5.212 1.292) (xy 5.212 -0.944)
			)
			(stroke
				(width 0.00186)
				(type solid)
			)
			(fill yes)
			(layer "B.Mask")
		)
		(fp_poly
			(pts
				(xy 8.164 1.321) (xy 8.193 1.317) (xy 8.204 1.31) (xy 8.204 1.308) (xy 8.2 1.285) (xy 8.188 1.24)
				(xy 8.171 1.181) (xy 8.163 1.156) (xy 8.142 1.092) (xy 8.126 1.053) (xy 8.112 1.034) (xy 8.097 1.031)
				(xy 8.094 1.032) (xy 7.996 1.053) (xy 7.886 1.06) (xy 7.778 1.053) (xy 7.683 1.032) (xy 7.665 1.026)
				(xy 7.622 1.009) (xy 7.622 -0.944) (xy 7.244 -0.944) (xy 7.244 1.178) (xy 7.358 1.219) (xy 7.457 1.253)
				(xy 7.548 1.277) (xy 7.639 1.295) (xy 7.738 1.307) (xy 7.856 1.315) (xy 7.94 1.319) (xy 8.042 1.322)
				(xy 8.115 1.322) (xy 8.164 1.321)
			)
			(stroke
				(width 0.00186)
				(type solid)
			)
			(fill yes)
			(layer "B.Mask")
		)
		(fp_poly
			(pts
				(xy 0.795 1.891) (xy 0.798 1.849) (xy 0.8 1.786) (xy 0.802 1.705) (xy 0.803 1.612) (xy 0.803 1.599)
				(xy 0.803 1.292) (xy 1.181 1.292) (xy 1.181 1.04) (xy 0.803 1.04) (xy 0.803 -0.498) (xy 0.838 -0.566)
				(xy 0.885 -0.631) (xy 0.944 -0.671) (xy 1.021 -0.688) (xy 1.082 -0.689) (xy 1.181 -0.685) (xy 1.181 -0.806)
				(xy 1.178 -0.88) (xy 1.17 -0.926) (xy 1.161 -0.939) (xy 1.138 -0.945) (xy 1.09 -0.95) (xy 1.028 -0.954)
				(xy 0.984 -0.956) (xy 0.897 -0.957) (xy 0.832 -0.953) (xy 0.778 -0.942) (xy 0.743 -0.931) (xy 0.647 -0.886)
				(xy 0.571 -0.823) (xy 0.508 -0.737) (xy 0.488 -0.701) (xy 0.433 -0.593) (xy 0.428 0.223) (xy 0.424 1.04)
				(xy 0.173 1.04) (xy 0.173 1.292) (xy 0.425 1.292) (xy 0.425 1.795) (xy 0.603 1.85) (xy 0.673 1.872)
				(xy 0.733 1.89) (xy 0.774 1.902) (xy 0.792 1.906) (xy 0.795 1.891)
			)
			(stroke
				(width 0.00186)
				(type solid)
			)
			(fill yes)
			(layer "B.Mask")
		)
		(fp_poly
			(pts
				(xy -0.82 1.315) (xy -0.737 1.312) (xy -0.672 1.308) (xy -0.621 1.301) (xy -0.577 1.291) (xy -0.56 1.286)
				(xy -0.417 1.232) (xy -0.302 1.164) (xy -0.212 1.082) (xy -0.154 0.996) (xy -0.135 0.961) (xy -0.119 0.927)
				(xy -0.105 0.893) (xy -0.094 0.855) (xy -0.085 0.811) (xy -0.078 0.758) (xy -0.073 0.693) (xy -0.069 0.612)
				(xy -0.067 0.515) (xy -0.065 0.397) (xy -0.064 0.256) (xy -0.064 0.088) (xy -0.063 -0.105) (xy -0.063 -0.944)
				(xy -0.441 -0.944) (xy -0.441 -0.113) (xy -0.442 0.083) (xy -0.442 0.25) (xy -0.443 0.391) (xy -0.445 0.508)
				(xy -0.448 0.604) (xy -0.452 0.682) (xy -0.457 0.744) (xy -0.465 0.794) (xy -0.474 0.833) (xy -0.486 0.864)
				(xy -0.501 0.89) (xy -0.518 0.913) (xy -0.538 0.937) (xy -0.539 0.939) (xy -0.604 0.997) (xy -0.684 1.039)
				(xy -0.784 1.066) (xy -0.822 1.072) (xy -0.927 1.078) (xy -1.044 1.073) (xy -1.158 1.056) (xy -1.24 1.034)
				(xy -1.3 1.013) (xy -1.304 0.034) (xy -1.308 -0.944) (xy -1.686 -0.944) (xy -1.686 1.178) (xy -1.54 1.225)
				(xy -1.44 1.257) (xy -1.354 1.28) (xy -1.276 1.297) (xy -1.195 1.307) (xy -1.105 1.313) (xy -0.995 1.315)
				(xy -0.93 1.315) (xy -0.82 1.315)
			)
			(stroke
				(width 0.00186)
				(type solid)
			)
			(fill yes)
			(layer "B.Mask")
		)
		(fp_poly
			(pts
				(xy 3.757 1.312) (xy 3.91 1.278) (xy 4.043 1.223) (xy 4.153 1.146) (xy 4.24 1.047) (xy 4.282 0.977)
				(xy 4.299 0.943) (xy 4.313 0.91) (xy 4.325 0.876) (xy 4.335 0.837) (xy 4.343 0.791) (xy 4.349 0.734)
				(xy 4.353 0.665) (xy 4.357 0.581) (xy 4.359 0.478) (xy 4.361 0.354) (xy 4.361 0.206) (xy 4.362 0.031)
				(xy 4.362 -0.111) (xy 4.362 -0.944) (xy 3.985 -0.944) (xy 3.98 -0.074) (xy 3.976 0.796) (xy 3.93 0.879)
				(xy 3.867 0.961) (xy 3.786 1.022) (xy 3.691 1.062) (xy 3.586 1.079) (xy 3.476 1.074) (xy 3.366 1.045)
				(xy 3.26 0.994) (xy 3.185 0.938) (xy 3.118 0.88) (xy 3.118 -0.944) (xy 2.74 -0.944) (xy 2.74 -0.092)
				(xy 2.739 0.122) (xy 2.739 0.305) (xy 2.737 0.459) (xy 2.735 0.585) (xy 2.732 0.683) (xy 2.729 0.755)
				(xy 2.725 0.802) (xy 2.722 0.821) (xy 2.679 0.91) (xy 2.613 0.981) (xy 2.523 1.034) (xy 2.413 1.067)
				(xy 2.284 1.079) (xy 2.154 1.073) (xy 2.082 1.064) (xy 2.031 1.056) (xy 1.989 1.046) (xy 1.944 1.031)
				(xy 1.917 1.021) (xy 1.874 1.005) (xy 1.874 -0.944) (xy 1.511 -0.944) (xy 1.511 1.18) (xy 1.661 1.228)
				(xy 1.83 1.276) (xy 1.988 1.306) (xy 2.148 1.319) (xy 2.314 1.319) (xy 2.448 1.311) (xy 2.557 1.297)
				(xy 2.649 1.272) (xy 2.732 1.237) (xy 2.811 1.189) (xy 2.843 1.165) (xy 2.947 1.087) (xy 3.012 1.14)
				(xy 3.14 1.224) (xy 3.283 1.283) (xy 3.443 1.315) (xy 3.582 1.323) (xy 3.757 1.312)
			)
			(stroke
				(width 0.00186)
				(type solid)
			)
			(fill yes)
			(layer "B.Mask")
		)
		(fp_poly
			(pts
				(xy 9.278 1.313) (xy 9.419 1.281) (xy 9.543 1.225) (xy 9.656 1.146) (xy 9.708 1.097) (xy 9.808 0.975)
				(xy 9.887 0.831) (xy 9.945 0.666) (xy 9.984 0.476) (xy 9.998 0.354) (xy 10.005 0.134) (xy 9.992 -0.072)
				(xy 9.96 -0.262) (xy 9.908 -0.434) (xy 9.837 -0.585) (xy 9.749 -0.714) (xy 9.643 -0.819) (xy 9.578 -0.867)
				(xy 9.475 -0.918) (xy 9.352 -0.956) (xy 9.219 -0.98) (xy 9.087 -0.986) (xy 8.966 -0.975) (xy 8.81 -0.933)
				(xy 8.673 -0.864) (xy 8.553 -0.771) (xy 8.452 -0.653) (xy 8.371 -0.511) (xy 8.31 -0.346) (xy 8.277 -0.202)
				(xy 8.249 0.011) (xy 8.243 0.182) (xy 8.619 0.182) (xy 8.626 0.007) (xy 8.647 -0.163) (xy 8.682 -0.318)
				(xy 8.73 -0.449) (xy 8.792 -0.552) (xy 8.87 -0.633) (xy 8.961 -0.69) (xy 9.06 -0.721) (xy 9.164 -0.724)
				(xy 9.268 -0.699) (xy 9.303 -0.683) (xy 9.391 -0.625) (xy 9.465 -0.546) (xy 9.524 -0.443) (xy 9.569 -0.315)
				(xy 9.601 -0.162) (xy 9.62 0) (xy 9.628 0.198) (xy 9.62 0.382) (xy 9.597 0.55) (xy 9.558 0.698)
				(xy 9.505 0.825) (xy 9.439 0.927) (xy 9.397 0.971) (xy 9.307 1.035) (xy 9.21 1.071) (xy 9.109 1.079)
				(xy 9.009 1.062) (xy 8.915 1.019) (xy 8.831 0.953) (xy 8.76 0.863) (xy 8.733 0.813) (xy 8.684 0.68)
				(xy 8.648 0.526) (xy 8.627 0.358) (xy 8.619 0.182) (xy 8.243 0.182) (xy 8.242 0.218) (xy 8.255 0.417)
				(xy 8.288 0.602) (xy 8.339 0.772) (xy 8.41 0.923) (xy 8.498 1.051) (xy 8.524 1.081) (xy 8.637 1.182)
				(xy 8.765 1.255) (xy 8.908 1.302) (xy 9.068 1.322) (xy 9.117 1.323) (xy 9.278 1.313)
			)
			(stroke
				(width 0.00186)
				(type solid)
			)
			(fill yes)
			(layer "B.Mask")
		)
		(fp_poly
			(pts
				(xy 6.48 1.32) (xy 6.584 1.31) (xy 6.642 1.3) (xy 6.701 1.282) (xy 6.765 1.259) (xy 6.825 1.233)
				(xy 6.873 1.209) (xy 6.9 1.189) (xy 6.902 1.186) (xy 6.901 1.166) (xy 6.889 1.128) (xy 6.872 1.079)
				(xy 6.852 1.03) (xy 6.833 0.989) (xy 6.818 0.966) (xy 6.815 0.963) (xy 6.795 0.969) (xy 6.757 0.985)
				(xy 6.717 1.002) (xy 6.597 1.044) (xy 6.478 1.06) (xy 6.365 1.05) (xy 6.267 1.016) (xy 6.184 0.957)
				(xy 6.109 0.87) (xy 6.042 0.76) (xy 5.988 0.629) (xy 5.964 0.554) (xy 5.946 0.461) (xy 5.934 0.347)
				(xy 5.929 0.22) (xy 5.931 0.091) (xy 5.938 -0.032) (xy 5.953 -0.138) (xy 5.965 -0.191) (xy 6.018 -0.347)
				(xy 6.085 -0.476) (xy 6.166 -0.576) (xy 6.262 -0.649) (xy 6.269 -0.653) (xy 6.318 -0.678) (xy 6.36 -0.692)
				(xy 6.409 -0.698) (xy 6.476 -0.7) (xy 6.48 -0.7) (xy 6.551 -0.697) (xy 6.613 -0.686) (xy 6.676 -0.665)
				(xy 6.75 -0.631) (xy 6.805 -0.602) (xy 6.811 -0.606) (xy 6.823 -0.627) (xy 6.842 -0.667) (xy 6.868 -0.73)
				(xy 6.904 -0.819) (xy 6.907 -0.827) (xy 6.898 -0.844) (xy 6.866 -0.868) (xy 6.818 -0.895) (xy 6.759 -0.922)
				(xy 6.697 -0.945) (xy 6.68 -0.95) (xy 6.596 -0.968) (xy 6.494 -0.98) (xy 6.388 -0.984) (xy 6.292 -0.98)
				(xy 6.251 -0.975) (xy 6.192 -0.96) (xy 6.121 -0.935) (xy 6.055 -0.906) (xy 5.924 -0.825) (xy 5.811 -0.718)
				(xy 5.717 -0.586) (xy 5.641 -0.431) (xy 5.585 -0.252) (xy 5.566 -0.164) (xy 5.552 -0.061) (xy 5.545 0.061)
				(xy 5.544 0.193) (xy 5.549 0.327) (xy 5.56 0.453) (xy 5.576 0.563) (xy 5.589 0.623) (xy 5.65 0.797)
				(xy 5.731 0.949) (xy 5.831 1.077) (xy 5.948 1.181) (xy 6.081 1.259) (xy 6.187 1.298) (xy 6.27 1.314)
				(xy 6.372 1.322) (xy 6.48 1.32)
			)
			(stroke
				(width 0.00186)
				(type solid)
			)
			(fill yes)
			(layer "B.Mask")
		)
		(fp_poly
			(pts
				(xy -2.763 1.313) (xy -2.663 1.294) (xy -2.55 1.259) (xy -2.459 1.216) (xy -2.38 1.16) (xy -2.341 1.124)
				(xy -2.284 1.053) (xy -2.232 0.961) (xy -2.192 0.861) (xy -2.174 0.79) (xy -2.17 0.754) (xy -2.167 0.69)
				(xy -2.164 0.599) (xy -2.162 0.485) (xy -2.16 0.35) (xy -2.159 0.196) (xy -2.158 0.027) (xy -2.158 -0.064)
				(xy -2.158 -0.833) (xy -2.232 -0.865) (xy -2.364 -0.913) (xy -2.517 -0.949) (xy -2.682 -0.974) (xy -2.85 -0.986)
				(xy -3.011 -0.983) (xy -3.097 -0.975) (xy -3.264 -0.942) (xy -3.407 -0.889) (xy -3.525 -0.817) (xy -3.618 -0.725)
				(xy -3.686 -0.616) (xy -3.729 -0.487) (xy -3.746 -0.341) (xy -3.746 -0.268) (xy -3.744 -0.254) (xy -3.383 -0.254)
				(xy -3.38 -0.384) (xy -3.352 -0.497) (xy -3.298 -0.591) (xy -3.221 -0.665) (xy -3.12 -0.719) (xy -3.072 -0.735)
				(xy -3.011 -0.745) (xy -2.928 -0.75) (xy -2.835 -0.75) (xy -2.74 -0.744) (xy -2.655 -0.734) (xy -2.589 -0.72)
				(xy -2.579 -0.716) (xy -2.504 -0.689) (xy -2.504 0.302) (xy -2.595 0.291) (xy -2.653 0.282) (xy -2.728 0.267)
				(xy -2.806 0.25) (xy -2.831 0.244) (xy -2.992 0.194) (xy -3.125 0.133) (xy -3.229 0.06) (xy -3.306 -0.026)
				(xy -3.357 -0.125) (xy -3.381 -0.238) (xy -3.383 -0.254) (xy -3.744 -0.254) (xy -3.725 -0.126) (xy -3.678 0)
				(xy -3.602 0.112) (xy -3.559 0.158) (xy -3.465 0.233) (xy -3.343 0.303) (xy -3.198 0.365) (xy -3.034 0.417)
				(xy -2.856 0.46) (xy -2.666 0.49) (xy -2.663 0.49) (xy -2.5 0.51) (xy -2.51 0.644) (xy -2.528 0.77)
				(xy -2.564 0.871) (xy -2.62 0.949) (xy -2.697 1.007) (xy -2.797 1.045) (xy -2.845 1.056) (xy -2.975 1.067)
				(xy -3.12 1.056) (xy -3.272 1.024) (xy -3.426 0.972) (xy -3.439 0.967) (xy -3.488 0.947) (xy -3.523 0.936)
				(xy -3.537 0.934) (xy -3.545 0.95) (xy -3.56 0.987) (xy -3.579 1.035) (xy -3.598 1.086) (xy -3.613 1.129)
				(xy -3.622 1.155) (xy -3.623 1.159) (xy -3.609 1.169) (xy -3.575 1.188) (xy -3.537 1.206) (xy -3.395 1.257)
				(xy -3.239 1.294) (xy -3.075 1.316) (xy -2.914 1.323) (xy -2.763 1.313)
			)
			(stroke
				(width 0.00186)
				(type solid)
			)
			(fill yes)
			(layer "B.Mask")
		)
		(fp_poly
			(pts
				(xy -7.153 3.366) (xy -7.087 3.351) (xy -7.086 3.351) (xy -7.066 3.34) (xy -7.021 3.315) (xy -6.953 3.277)
				(xy -6.865 3.227) (xy -6.759 3.167) (xy -6.639 3.099) (xy -6.505 3.022) (xy -6.361 2.94) (xy -6.209 2.853)
				(xy -6.052 2.762) (xy -5.891 2.67) (xy -5.729 2.577) (xy -5.569 2.485) (xy -5.413 2.395) (xy -5.264 2.309)
				(xy -5.123 2.227) (xy -4.994 2.152) (xy -4.878 2.085) (xy -4.778 2.027) (xy -4.697 1.979) (xy -4.636 1.943)
				(xy -4.599 1.921) (xy -4.595 1.918) (xy -4.528 1.863) (xy -4.476 1.798) (xy -4.434 1.725) (xy -4.429 0.224)
				(xy -4.429 -0.063) (xy -4.428 -0.323) (xy -4.429 -0.553) (xy -4.429 -0.755) (xy -4.43 -0.928) (xy -4.432 -1.071)
				(xy -4.434 -1.184) (xy -4.436 -1.266) (xy -4.439 -1.318) (xy -4.441 -1.337) (xy -4.448 -1.36) (xy -4.454 -1.382)
				(xy -4.463 -1.403) (xy -4.476 -1.423) (xy -4.494 -1.445) (xy -4.519 -1.47) (xy -4.552 -1.497) (xy -4.596 -1.529)
				(xy -4.652 -1.567) (xy -4.721 -1.611) (xy -4.805 -1.663) (xy -4.906 -1.723) (xy -5.025 -1.794) (xy -5.165 -1.875)
				(xy -5.326 -1.969) (xy -5.511 -2.076) (xy -5.72 -2.197) (xy -5.813 -2.251) (xy -7.079 -2.982) (xy -7.197 -2.988)
				(xy -7.315 -2.994) (xy -7.78 -2.727) (xy -8.064 -2.563) (xy -8.323 -2.415) (xy -8.557 -2.28) (xy -8.767 -2.159)
				(xy -8.955 -2.051) (xy -9.122 -1.954) (xy -9.27 -1.868) (xy -9.399 -1.792) (xy -9.51 -1.726) (xy -9.606 -1.669)
				(xy -9.688 -1.619) (xy -9.756 -1.576) (xy -9.812 -1.539) (xy -9.857 -1.507) (xy -9.893 -1.481) (xy -9.92 -1.458)
				(xy -9.94 -1.437) (xy -9.955 -1.42) (xy -9.965 -1.403) (xy -9.972 -1.387) (xy -9.977 -1.371) (xy -9.981 -1.354)
				(xy -9.985 -1.337) (xy -9.988 -1.309) (xy -9.991 -1.25) (xy -9.993 -1.161) (xy -9.995 -1.041) (xy -9.996 -0.891)
				(xy -9.997 -0.712) (xy -9.998 -0.503) (xy -9.998 -0.266) (xy -9.997 0) (xy -9.997 0.189) (xy -9.024 0.189)
				(xy -9.024 -0.015) (xy -9.024 -0.191) (xy -9.023 -0.34) (xy -9.022 -0.464) (xy -9.021 -0.567) (xy -9.018 -0.65)
				(xy -9.014 -0.717) (xy -9.01 -0.768) (xy -9.003 -0.808) (xy -8.995 -0.837) (xy -8.986 -0.859) (xy -8.974 -0.876)
				(xy -8.961 -0.891) (xy -8.945 -0.905) (xy -8.943 -0.906) (xy -8.922 -0.921) (xy -8.877 -0.949) (xy -8.81 -0.989)
				(xy -8.725 -1.039) (xy -8.625 -1.098) (xy -8.512 -1.164) (xy -8.389 -1.235) (xy -8.26 -1.31) (xy -8.128 -1.386)
				(xy -7.995 -1.463) (xy -7.864 -1.538) (xy -7.739 -1.609) (xy -7.622 -1.676) (xy -7.517 -1.735) (xy -7.425 -1.787)
				(xy -7.351 -1.828) (xy -7.297 -1.857) (xy -7.266 -1.872) (xy -7.261 -1.874) (xy -7.222 -1.885) (xy -7.195 -1.886)
				(xy -7.163 -1.875) (xy -7.144 -1.867) (xy -7.117 -1.854) (xy -7.067 -1.827) (xy -6.997 -1.788) (xy -6.909 -1.738)
				(xy -6.805 -1.679) (xy -6.691 -1.614) (xy -6.567 -1.543) (xy -6.438 -1.469) (xy -6.306 -1.392) (xy -6.174 -1.316)
				(xy -6.045 -1.241) (xy -5.922 -1.17) (xy -5.809 -1.103) (xy -5.708 -1.044) (xy -5.622 -0.992) (xy -5.553 -0.952)
				(xy -5.507 -0.923) (xy -5.484 -0.907) (xy -5.483 -0.907) (xy -5.467 -0.892) (xy -5.453 -0.878) (xy -5.441 -0.861)
				(xy -5.431 -0.839) (xy -5.423 -0.81) (xy -5.417 -0.772) (xy -5.412 -0.721) (xy -5.408 -0.656) (xy -5.406 -0.574)
				(xy -5.404 -0.473) (xy -5.403 -0.35) (xy -5.402 -0.203) (xy -5.402 -0.03) (xy -5.402 0.172) (xy -5.402 0.189)
				(xy -5.402 0.395) (xy -5.402 0.572) (xy -5.403 0.721) (xy -5.404 0.847) (xy -5.406 0.95) (xy -5.408 1.034)
				(xy -5.412 1.101) (xy -5.418 1.153) (xy -5.425 1.193) (xy -5.434 1.223) (xy -5.445 1.245) (xy -5.458 1.262)
				(xy -5.473 1.276) (xy -5.491 1.29) (xy -5.499 1.295) (xy -5.522 1.31) (xy -5.57 1.339) (xy -5.64 1.381)
				(xy -5.729 1.433) (xy -5.835 1.496) (xy -5.956 1.566) (xy -6.088 1.643) (xy -6.229 1.725) (xy -6.348 1.793)
				(xy -6.519 1.891) (xy -6.664 1.974) (xy -6.786 2.044) (xy -6.888 2.101) (xy -6.971 2.147) (xy -7.038 2.183)
				(xy -7.091 2.21) (xy -7.132 2.229) (xy -7.163 2.242) (xy -7.187 2.249) (xy -7.205 2.252) (xy -7.211 2.252)
				(xy -7.228 2.251) (xy -7.249 2.246) (xy -7.276 2.236) (xy -7.312 2.219) (xy -7.359 2.196) (xy -7.419 2.165)
				(xy -7.495 2.123) (xy -7.587 2.072) (xy -7.699 2.008) (xy -7.832 1.932) (xy -7.99 1.842) (xy -8.1 1.778)
				(xy -8.248 1.693) (xy -8.388 1.611) (xy -8.519 1.535) (xy -8.637 1.466) (xy -8.739 1.406) (xy -8.825 1.355)
				(xy -8.89 1.316) (xy -8.933 1.29) (xy -8.951 1.278) (xy -8.966 1.265) (xy -8.978 1.251) (xy -8.989 1.234)
				(xy -8.998 1.212) (xy -9.005 1.182) (xy -9.011 1.141) (xy -9.015 1.087) (xy -9.018 1.019) (xy -9.021 0.933)
				(xy -9.022 0.827) (xy -9.023 0.699) (xy -9.024 0.546) (xy -9.024 0.366) (xy -9.024 0.189) (xy -9.997 0.189)
				(xy -9.997 0.224) (xy -9.996 0.479) (xy -9.996 0.705) (xy -9.995 0.903) (xy -9.994 1.075) (xy -9.993 1.223)
				(xy -9.992 1.35) (xy -9.99 1.456) (xy -9.987 1.545) (xy -9.984 1.617) (xy -9.98 1.675) (xy -9.974 1.721)
				(xy -9.968 1.757) (xy -9.961 1.784) (xy -9.952 1.805) (xy -9.941 1.821) (xy -9.929 1.834) (xy -9.915 1.847)
				(xy -9.9 1.86) (xy -9.893 1.866) (xy -9.873 1.88) (xy -9.828 1.909) (xy -9.759 1.951) (xy -9.669 2.005)
				(xy -9.56 2.07) (xy -9.433 2.145) (xy -9.291 2.228) (xy -9.136 2.319) (xy -8.969 2.416) (xy -8.793 2.518)
				(xy -8.61 2.624) (xy -8.59 2.635) (xy -8.377 2.759) (xy -8.189 2.867) (xy -8.024 2.962) (xy -7.882 3.044)
				(xy -7.759 3.114) (xy -7.656 3.173) (xy -7.568 3.221) (xy -7.496 3.261) (xy -7.437 3.293) (xy -7.389 3.317)
				(xy -7.351 3.336) (xy -7.321 3.349) (xy -7.296 3.357) (xy -7.276 3.363) (xy -7.259 3.366) (xy -7.242 3.367)
				(xy -7.237 3.368) (xy -7.153 3.366)
			)
			(stroke
				(width 0.00186)
				(type solid)
			)
			(fill yes)
			(layer "B.Mask")
		)
		(fp_poly
			(pts
				(xy -7.128 1.48) (xy -7.114 1.475) (xy -7.042 1.428) (xy -6.989 1.361) (xy -6.96 1.281) (xy -6.957 1.196)
				(xy -6.961 1.175) (xy -6.992 1.094) (xy -7.046 1.034) (xy -7.101 1.001) (xy -7.166 0.969) (xy -7.166 0.599)
				(xy -6.891 0.599) (xy -6.778 0.711) (xy -6.665 0.824) (xy -6.673 0.905) (xy -6.673 0.906) (xy -6.566 0.906)
				(xy -6.549 0.87) (xy -6.512 0.853) (xy -6.467 0.856) (xy -6.435 0.876) (xy -6.412 0.913) (xy -6.42 0.95)
				(xy -6.441 0.977) (xy -6.471 1.002) (xy -6.496 1.005) (xy -6.53 0.986) (xy -6.532 0.984) (xy -6.56 0.949)
				(xy -6.566 0.906) (xy -6.673 0.906) (xy -6.676 0.957) (xy -6.669 0.992) (xy -6.648 1.025) (xy -6.639 1.036)
				(xy -6.582 1.084) (xy -6.519 1.106) (xy -6.456 1.105) (xy -6.397 1.084) (xy -6.349 1.044) (xy -6.316 0.99)
				(xy -6.304 0.925) (xy -6.315 0.859) (xy -6.351 0.797) (xy -6.408 0.757) (xy -6.484 0.741) (xy -6.497 0.741)
				(xy -6.529 0.74) (xy -6.557 0.734) (xy -6.585 0.719) (xy -6.619 0.693) (xy -6.667 0.651) (xy -6.705 0.615)
				(xy -6.84 0.489) (xy -7.166 0.489) (xy -7.166 0.237) (xy -6.568 0.237) (xy -6.545 0.282) (xy -6.502 0.333)
				(xy -6.443 0.364) (xy -6.377 0.373) (xy -6.311 0.36) (xy -6.255 0.322) (xy -6.249 0.317) (xy -6.209 0.253)
				(xy -6.195 0.188) (xy -6.205 0.126) (xy -6.234 0.072) (xy -6.28 0.03) (xy -6.337 0.006) (xy -6.402 0.002)
				(xy -6.472 0.025) (xy -6.486 0.033) (xy -6.523 0.061) (xy -6.545 0.091) (xy -6.547 0.096) (xy -6.552 0.106)
				(xy -6.561 0.114) (xy -6.58 0.12) (xy -6.613 0.123) (xy -6.664 0.125) (xy -6.737 0.126) (xy -6.836 0.126)
				(xy -6.861 0.126) (xy -7.166 0.126) (xy -7.166 -0.11) (xy -6.842 -0.11) (xy -6.581 -0.373) (xy -6.507 -0.366)
				(xy -6.428 -0.372) (xy -6.367 -0.402) (xy -6.325 -0.457) (xy -6.314 -0.486) (xy -6.304 -0.561) (xy -6.322 -0.626)
				(xy -6.361 -0.678) (xy -6.422 -0.72) (xy -6.487 -0.736) (xy -6.55 -0.727) (xy -6.605 -0.697) (xy -6.648 -0.648)
				(xy -6.671 -0.583) (xy -6.672 -0.536) (xy -6.564 -0.536) (xy -6.559 -0.575) (xy -6.544 -0.597) (xy -6.508 -0.625)
				(xy -6.474 -0.623) (xy -6.441 -0.598) (xy -6.414 -0.56) (xy -6.417 -0.525) (xy -6.44 -0.497) (xy -6.48 -0.476)
				(xy -6.518 -0.48) (xy -6.549 -0.502) (xy -6.564 -0.536) (xy -6.672 -0.536) (xy -6.673 -0.52) (xy -6.664 -0.445)
				(xy -6.891 -0.22) (xy -7.166 -0.22) (xy -7.166 -0.593) (xy -7.101 -0.622) (xy -7.033 -0.668) (xy -6.986 -0.732)
				(xy -6.96 -0.805) (xy -6.956 -0.883) (xy -6.973 -0.959) (xy -7.013 -1.026) (xy -7.074 -1.079) (xy -7.088 -1.087)
				(xy -7.171 -1.112) (xy -7.258 -1.112) (xy -7.34 -1.087) (xy -7.341 -1.086) (xy -7.406 -1.036) (xy -7.448 -0.97)
				(xy -7.469 -0.895) (xy -7.468 -0.858) (xy -7.361 -0.858) (xy -7.355 -0.905) (xy -7.331 -0.942) (xy -7.31 -0.962)
				(xy -7.252 -0.999) (xy -7.195 -1.005) (xy -7.137 -0.979) (xy -7.116 -0.962) (xy -7.08 -0.923) (xy -7.066 -0.883)
				(xy -7.065 -0.858) (xy -7.079 -0.801) (xy -7.116 -0.751) (xy -7.167 -0.718) (xy -7.213 -0.708) (xy -7.27 -0.722)
				(xy -7.319 -0.76) (xy -7.352 -0.812) (xy -7.361 -0.858) (xy -7.468 -0.858) (xy -7.468 -0.817) (xy -7.445 -0.742)
				(xy -7.401 -0.677) (xy -7.336 -0.628) (xy -7.325 -0.622) (xy -7.26 -0.593) (xy -7.26 -0.22) (xy -7.535 -0.22)
				(xy -7.762 -0.445) (xy -7.753 -0.52) (xy -7.757 -0.595) (xy -7.785 -0.658) (xy -7.83 -0.703) (xy -7.887 -0.73)
				(xy -7.951 -0.735) (xy -8.015 -0.715) (xy -8.065 -0.678) (xy -8.109 -0.617) (xy -8.123 -0.551) (xy -8.12 -0.532)
				(xy -8.012 -0.532) (xy -8.009 -0.566) (xy -7.985 -0.598) (xy -7.946 -0.625) (xy -7.912 -0.623) (xy -7.883 -0.599)
				(xy -7.863 -0.558) (xy -7.868 -0.517) (xy -7.896 -0.486) (xy -7.915 -0.478) (xy -7.961 -0.48) (xy -7.985 -0.496)
				(xy -8.012 -0.532) (xy -8.12 -0.532) (xy -8.112 -0.486) (xy -8.079 -0.422) (xy -8.025 -0.381) (xy -7.953 -0.365)
				(xy -7.919 -0.366) (xy -7.845 -0.373) (xy -7.584 -0.11) (xy -7.26 -0.11) (xy -7.26 0.126) (xy -7.566 0.126)
				(xy -7.672 0.126) (xy -7.75 0.126) (xy -7.805 0.124) (xy -7.841 0.121) (xy -7.863 0.116) (xy -7.875 0.108)
				(xy -7.881 0.098) (xy -7.883 0.094) (xy -7.908 0.058) (xy -7.954 0.026) (xy -8.009 0.005) (xy -8.045 0.001)
				(xy -8.117 0.014) (xy -8.174 0.049) (xy -8.213 0.102) (xy -8.23 0.164) (xy -8.228 0.186) (xy -8.124 0.186)
				(xy -8.12 0.163) (xy -8.104 0.143) (xy -8.063 0.115) (xy -8.021 0.117) (xy -7.994 0.135) (xy -7.971 0.176)
				(xy -7.976 0.202) (xy -6.455 0.202) (xy -6.449 0.158) (xy -6.432 0.135) (xy -6.392 0.113) (xy -6.35 0.121)
				(xy -6.322 0.143) (xy -6.303 0.169) (xy -6.304 0.193) (xy -6.316 0.218) (xy -6.35 0.254) (xy -6.39 0.265)
				(xy -6.429 0.247) (xy -6.432 0.244) (xy -6.455 0.202) (xy -7.976 0.202) (xy -7.979 0.218) (xy -7.999 0.244)
				(xy -8.04 0.265) (xy -8.078 0.255) (xy -8.11 0.218) (xy -8.124 0.186) (xy -8.228 0.186) (xy -8.224 0.232)
				(xy -8.192 0.297) (xy -8.177 0.317) (xy -8.121 0.358) (xy -8.055 0.374) (xy -7.988 0.365) (xy -7.927 0.333)
				(xy -7.885 0.284) (xy -7.857 0.237) (xy -7.26 0.237) (xy -7.26 0.489) (xy -7.586 0.489) (xy -7.721 0.615)
				(xy -7.779 0.669) (xy -7.821 0.704) (xy -7.852 0.726) (xy -7.879 0.737) (xy -7.908 0.74) (xy -7.934 0.741)
				(xy -8.011 0.752) (xy -8.068 0.787) (xy -8.105 0.846) (xy -8.112 0.866) (xy -8.119 0.923) (xy -8.016 0.923)
				(xy -8.003 0.887) (xy -7.969 0.862) (xy -7.928 0.852) (xy -7.888 0.861) (xy -7.878 0.87) (xy -7.86 0.907)
				(xy -7.866 0.949) (xy -7.894 0.984) (xy -7.924 1.002) (xy -7.941 1.008) (xy -7.964 0.997) (xy -7.991 0.969)
				(xy -8.011 0.939) (xy -8.016 0.923) (xy -8.119 0.923) (xy -8.121 0.94) (xy -8.105 1.004) (xy -8.069 1.055)
				(xy -8.018 1.091) (xy -7.958 1.108) (xy -7.894 1.104) (xy -7.831 1.076) (xy -7.787 1.036) (xy -7.762 1.001)
				(xy -7.751 0.968) (xy -7.751 0.923) (xy -7.753 0.905) (xy -7.762 0.824) (xy -7.648 0.711) (xy -7.535 0.599)
				(xy -7.26 0.599) (xy -7.26 0.971) (xy -7.323 0.998) (xy -7.396 1.046) (xy -7.446 1.114) (xy -7.465 1.166)
				(xy -7.472 1.24) (xy -7.365 1.24) (xy -7.359 1.204) (xy -7.347 1.177) (xy -7.307 1.123) (xy -7.254 1.093)
				(xy -7.194 1.09) (xy -7.134 1.116) (xy -7.127 1.121) (xy -7.081 1.171) (xy -7.065 1.225) (xy -7.078 1.283)
				(xy -7.116 1.342) (xy -7.166 1.375) (xy -7.222 1.384) (xy -7.278 1.368) (xy -7.326 1.326) (xy -7.354 1.278)
				(xy -7.365 1.24) (xy -7.472 1.24) (xy -7.474 1.25) (xy -7.455 1.328) (xy -7.416 1.396) (xy -7.358 1.449)
				(xy -7.288 1.484) (xy -7.21 1.495) (xy -7.128 1.48)
			)
			(stroke
				(width 0.00186)
				(type solid)
			)
			(fill yes)
			(layer "B.Mask")
		)
	)
	(gr_arc
		(start 110.800046 108.425033)
		(mid 111.508444 108.732278)
		(end 111.8 109.447277)
		(stroke
			(width 0.12)
			(type solid)
		)
		(layer "Edge.Cuts")
	)
	(gr_line
		(start 186.214895 87.667277)
		(end 111.600038 87.667277)
		(stroke
			(width 0.12)
			(type solid)
		)
		(layer "Edge.Cuts")
	)
	(gr_line
		(start 151.610059 121.387277)
		(end 151.610059 109.517277)
		(stroke
			(width 0.12)
			(type solid)
		)
		(layer "Edge.Cuts")
	)
	(gr_line
		(start 151.610059 121.387277)
		(end 111.800059 121.397277)
		(stroke
			(width 0.12)
			(type solid)
		)
		(layer "Edge.Cuts")
	)
	(gr_line
		(start 111.800059 121.397277)
		(end 111.8 109.447277)
		(stroke
			(width 0.12)
			(type solid)
		)
		(layer "Edge.Cuts")
	)
	(gr_line
		(start 110.600042 88.670111)
		(end 106.200042 88.670111)
		(stroke
			(width 0.12)
			(type solid)
		)
		(layer "Edge.Cuts")
	)
	(gr_line
		(start 109.100059 105.224442)
		(end 106.200059 105.224442)
		(stroke
			(width 0.12)
			(type solid)
		)
		(layer "Edge.Cuts")
	)
	(gr_line
		(start 106.200059 104.070111)
		(end 109.100042 104.070111)
		(stroke
			(width 0.12)
			(type solid)
		)
		(layer "Edge.Cuts")
	)
	(gr_arc
		(start 109.100042 104.070111)
		(mid 109.655114 104.647268)
		(end 109.100059 105.224442)
		(stroke
			(width 0.12)
			(type solid)
		)
		(layer "Edge.Cuts")
	)
	(gr_line
		(start 106.200042 88.670111)
		(end 106.200042 104.070111)
		(stroke
			(width 0.12)
			(type solid)
		)
		(layer "Edge.Cuts")
	)
	(gr_arc
		(start 111.600038 87.667277)
		(mid 111.30815 88.376215)
		(end 110.600042 88.670111)
		(stroke
			(width 0.12)
			(type solid)
		)
		(layer "Edge.Cuts")
	)
	(gr_line
		(start 186.2 109.512501)
		(end 186.214895 87.667277)
		(stroke
			(width 0.12)
			(type solid)
		)
		(layer "Edge.Cuts")
	)
	(gr_line
		(start 106.200059 105.224442)
		(end 106.200059 108.424442)
		(stroke
			(width 0.12)
			(type solid)
		)
		(layer "Edge.Cuts")
	)
	(gr_line
		(start 151.610059 109.517277)
		(end 186.2 109.512501)
		(stroke
			(width 0.12)
			(type solid)
		)
		(layer "Edge.Cuts")
	)
	(gr_line
		(start 106.200059 108.424442)
		(end 110.800046 108.425033)
		(stroke
			(width 0.12)
			(type solid)
		)
		(layer "Edge.Cuts")
	)
	(gr_text "M.2 PCIe x4 adapter"
		(at 143.350059 94.337277 0)
		(layer "B.Cu")
		(effects
			(font
				(size 0.6 0.6)
				(thickness 0.1)
			)
			(justify mirror)
		)
	)
	(gr_text "Rev. 1.2.2 06/2024"
		(at 144.190059 95.527277 0)
		(layer "B.Cu")
		(effects
			(font
				(size 0.5 0.5)
				(thickness 0.1)
			)
			(justify mirror)
		)
	)
	(segment
		(start 137.200059 110.576185)
		(end 137.770059 111.146185)
		(width 0.25)
		(layer "F.Cu")
		(net 5)
	)
	(segment
		(start 137.200059 110.187277)
		(end 137.200059 110.576185)
		(width 0.25)
		(layer "F.Cu")
		(net 5)
	)
	(segment
		(start 137.770059 115.677277)
		(end 138.210059 116.117277)
		(width 0.25)
		(layer "F.Cu")
		(net 5)
	)
	(segment
		(start 138.210059 116.117277)
		(end 138.210059 118.812263)
		(width 0.25)
		(layer "F.Cu")
		(net 5)
	)
	(segment
		(start 137.770059 111.146185)
		(end 137.770059 115.677277)
		(width 0.25)
		(layer "F.Cu")
		(net 5)
	)
	(via
		(at 137.200059 110.187277)
		(size 0.55)
		(drill 0.25)
		(layers "F.Cu" "B.Cu")
		(net 5)
	)
	(segment
		(start 137.200059 109.522277)
		(end 137.200059 110.187277)
		(width 0.25)
		(layer "B.Cu")
		(net 5)
	)
	(segment
		(start 138.210059 116.137277)
		(end 137.595059 115.522277)
		(width 0.25)
		(layer "B.Cu")
		(net 11)
	)
	(segment
		(start 135.680059 115.047277)
		(end 135.680059 109.572277)
		(width 0.25)
		(layer "B.Cu")
		(net 11)
	)
	(segment
		(start 136.155059 115.522277)
		(end 135.680059 115.047277)
		(width 0.25)
		(layer "B.Cu")
		(net 11)
	)
	(segment
		(start 137.595059 115.522277)
		(end 136.155059 115.522277)
		(width 0.25)
		(layer "B.Cu")
		(net 11)
	)
	(segment
		(start 138.210059 118.807309)
		(end 138.210059 116.137277)
		(width 0.25)
		(layer "B.Cu")
		(net 11)
	)
	(segment
		(start 112.970059 104.247277)
		(end 110.774816 102.052034)
		(width 0.25)
		(layer "F.Cu")
		(net 22)
	)
	(segment
		(start 112.970059 104.297277)
		(end 112.970059 104.247277)
		(width 0.25)
		(layer "F.Cu")
		(net 22)
	)
	(segment
		(start 110.774816 102.052034)
		(end 107.91861 102.052034)
		(width 0.25)
		(layer "F.Cu")
		(net 22)
	)
	(via
		(at 112.970059 104.297277)
		(size 0.55)
		(drill 0.25)
		(layers "F.Cu" "B.Cu")
		(net 22)
	)
	(segment
		(start 112.840059 104.427277)
		(end 112.000059 104.427277)
		(width 0.25)
		(layer "B.Cu")
		(net 22)
	)
	(segment
		(start 112.970059 104.297277)
		(end 112.840059 104.427277)
		(width 0.25)
		(layer "B.Cu")
		(net 22)
	)
	(segment
		(start 148.210059 118.812263)
		(end 148.210059 110.167277)
		(width 0.4)
		(layer "F.Cu")
		(net 30)
	)
	(segment
		(start 146.220059 112.357277)
		(end 146.210059 112.367277)
		(width 0.4)
		(layer "F.Cu")
		(net 30)
	)
	(segment
		(start 176.960059 102.877277)
		(end 180.860059 102.877277)
		(width 1.5)
		(layer "F.Cu")
		(net 30)
	)
	(segment
		(start 147.210059 110.267277)
		(end 147.110059 110.167277)
		(width 0.4)
		(layer "F.Cu")
		(net 30)
	)
	(segment
		(start 147.210059 118.812263)
		(end 147.210059 110.267277)
		(width 0.4)
		(layer "F.Cu")
		(net 30)
	)
	(segment
		(start 146.210059 114.017277)
		(end 146.210059 112.367277)
		(width 0.4)
		(layer "F.Cu")
		(net 30)
	)
	(segment
		(start 175.590059 101.507277)
		(end 176.960059 102.877277)
		(width 1.5)
		(layer "F.Cu")
		(net 30)
	)
	(segment
		(start 146.010059 110.167277)
		(end 146.220059 110.377277)
		(width 0.4)
		(layer "F.Cu")
		(net 30)
	)
	(segment
		(start 146.210059 110.367277)
		(end 146.010059 110.167277)
		(width 0.25)
		(layer "F.Cu")
		(net 30)
	)
	(segment
		(start 146.220059 110.377277)
		(end 146.220059 112.357277)
		(width 0.4)
		(layer "F.Cu")
		(net 30)
	)
	(segment
		(start 146.210059 118.812263)
		(end 146.210059 114.017277)
		(width 0.4)
		(layer "F.Cu")
		(net 30)
	)
	(segment
		(start 175.590059 96.137277)
		(end 175.590059 101.507277)
		(width 1.5)
		(layer "F.Cu")
		(net 30)
	)
	(via
		(at 147.110059 110.167277)
		(size 0.6)
		(drill 0.3)
		(layers "F.Cu" "B.Cu")
		(net 30)
	)
	(via
		(at 146.010059 110.167277)
		(size 0.6)
		(drill 0.3)
		(layers "F.Cu" "B.Cu")
		(net 30)
	)
	(segment
		(start 146.210059 110.217279)
		(end 146.210057 110.217277)
		(width 0.25)
		(layer "B.Cu")
		(net 30)
	)
	(segment
		(start 146.010059 110.167277)
		(end 146.210059 110.367277)
		(width 0.4)
		(layer "B.Cu")
		(net 30)
	)
	(segment
		(start 147.210059 118.812277)
		(end 147.210059 110.167277)
		(width 0.4)
		(layer "B.Cu")
		(net 30)
	)
	(segment
		(start 146.210059 114.017277)
		(end 146.210059 118.812277)
		(width 0.4)
		(layer "B.Cu")
		(net 30)
	)
	(segment
		(start 146.210059 110.367277)
		(end 146.210059 112.367277)
		(width 0.4)
		(layer "B.Cu")
		(net 30)
	)
	(segment
		(start 146.210059 114.017277)
		(end 146.210059 112.367277)
		(width 0.4)
		(layer "B.Cu")
		(net 30)
	)
	(segment
		(start 107.900059 106.522277)
		(end 110.025059 106.522277)
		(width 0.2)
		(layer "F.Cu")
		(net 31)
	)
	(segment
		(start 141.210059 115.357277)
		(end 141.210059 118.812263)
		(width 0.25)
		(layer "F.Cu")
		(net 31)
	)
	(segment
		(start 140.835059 114.982277)
		(end 141.210059 115.357277)
		(width 0.25)
		(layer "F.Cu")
		(net 31)
	)
	(segment
		(start 110.795302 93.052034)
		(end 110.800059 93.047277)
		(width 0.25)
		(layer "F.Cu")
		(net 31)
	)
	(segment
		(start 107.91861 93.052034)
		(end 110.795302 93.052034)
		(width 0.25)
		(layer "F.Cu")
		(net 31)
	)
	(segment
		(start 107.91861 93.552034)
		(end 110.800059 93.552034)
		(width 0.25)
		(layer "F.Cu")
		(net 31)
	)
	(segment
		(start 107.91861 92.052034)
		(end 110.845302 92.052034)
		(width 0.25)
		(layer "F.Cu")
		(net 31)
	)
	(segment
		(start 107.91861 90.052034)
		(end 111.000059 90.052034)
		(width 0.25)
		(layer "F.Cu")
		(net 31)
	)
	(segment
		(start 107.91861 89.552034)
		(end 111.000059 89.552034)
		(width 0.25)
		(layer "F.Cu")
		(net 31)
	)
	(segment
		(start 107.91861 92.552034)
		(end 110.800059 92.552034)
		(width 0.25)
		(layer "F.Cu")
		(net 31)
	)
	(via
		(at 140.835059 114.982277)
		(size 0.55)
		(drill 0.25)
		(layers "F.Cu" "B.Cu")
		(net 31)
	)
	(via
		(at 137.950059 103.147277)
		(size 0.55)
		(drill 0.25)
		(layers "F.Cu" "B.Cu")
		(net 31)
	)
	(via
		(at 140.201725 103.137277)
		(size 0.6)
		(drill 0.3)
		(layers "F.Cu" "B.Cu")
		(net 31)
	)
	(via
		(at 112.140059 88.567277)
		(size 0.55)
		(drill 0.25)
		(layers "F.Cu" "B.Cu")
		(net 31)
	)
	(via
		(at 139.213392 103.137277)
		(size 0.6)
		(drill 0.3)
		(layers "F.Cu" "B.Cu")
		(net 31)
	)
	(segment
		(start 140.210059 115.607277)
		(end 141.800059 114.017277)
		(width 0.25)
		(layer "B.Cu")
		(net 31)
	)
	(segment
		(start 141.800059 114.017277)
		(end 141.800059 112.497277)
		(width 0.25)
		(layer "B.Cu")
		(net 31)
	)
	(segment
		(start 141.800059 111.217277)
		(end 141.820059 111.197277)
		(width 0.25)
		(layer "B.Cu")
		(net 31)
	)
	(segment
		(start 140.201725 108.048943)
		(end 141.800059 109.647277)
		(width 0.25)
		(layer "B.Cu")
		(net 31)
	)
	(segment
		(start 141.800059 112.497277)
		(end 141.800059 111.217277)
		(width 0.25)
		(layer "B.Cu")
		(net 31)
	)
	(segment
		(start 141.710059 112.407277)
		(end 141.520059 112.407277)
		(width 0.25)
		(layer "B.Cu")
		(net 31)
	)
	(segment
		(start 139.210059 118.807309)
		(end 139.210059 103.14061)
		(width 0.25)
		(layer "B.Cu")
		(net 31)
	)
	(segment
		(start 141.800059 111.177277)
		(end 141.820059 111.197277)
		(width 0.25)
		(layer "B.Cu")
		(net 31)
	)
	(segment
		(start 141.520059 112.539777)
		(end 141.520059 112.407277)
		(width 0.25)
		(layer "B.Cu")
		(net 31)
	)
	(segment
		(start 138.000059 103.197277)
		(end 138.000059 106.467277)
		(width 0.25)
		(layer "B.Cu")
		(net 31)
	)
	(segment
		(start 112.140059 88.567277)
		(end 113.190059 88.567277)
		(width 0.25)
		(layer "B.Cu")
		(net 31)
	)
	(segment
		(start 141.800059 112.497277)
		(end 141.710059 112.407277)
		(width 0.25)
		(layer "B.Cu")
		(net 31)
	)
	(segment
		(start 137.950059 103.147277)
		(end 138.000059 103.197277)
		(width 0.25)
		(layer "B.Cu")
		(net 31)
	)
	(segment
		(start 140.210059 118.807309)
		(end 140.210059 115.607277)
		(width 0.25)
		(layer "B.Cu")
		(net 31)
	)
	(segment
		(start 140.201725 103.137277)
		(end 140.201725 108.048943)
		(width 0.25)
		(layer "B.Cu")
		(net 31)
	)
	(segment
		(start 139.210059 103.14061)
		(end 139.213392 103.137277)
		(width 0.25)
		(layer "B.Cu")
		(net 31)
	)
	(segment
		(start 141.800059 112.497277)
		(end 141.520059 112.217277)
		(width 0.25)
		(layer "B.Cu")
		(net 31)
	)
	(segment
		(start 141.800059 109.647277)
		(end 141.800059 111.177277)
		(width 0.25)
		(layer "B.Cu")
		(net 31)
	)
	(segment
		(start 134.56058 110.767798)
		(end 134.56058 110.400102)
		(width 0.185)
		(layer "F.Cu")
		(net 32)
	)
	(segment
		(start 134.855059 105.116922)
		(end 135.255311 104.71667)
		(width 0.185)
		(layer "F.Cu")
		(net 32)
	)
	(segment
		(start 134.855059 110.105623)
		(end 134.855059 105.116922)
		(width 0.185)
		(layer "F.Cu")
		(net 32)
	)
	(segment
		(start 134.56058 110.400102)
		(end 134.855059 110.105623)
		(width 0.185)
		(layer "F.Cu")
		(net 32)
	)
	(segment
		(start 135.255311 104.71667)
		(end 135.538153 104.71667)
		(width 0.185)
		(layer "F.Cu")
		(net 32)
	)
	(via
		(at 134.56058 110.767798)
		(size 0.6)
		(drill 0.3)
		(layers "F.Cu" "B.Cu")
		(net 32)
	)
	(via
		(at 135.538153 104.71667)
		(size 0.55)
		(drill 0.25)
		(layers "F.Cu" "B.Cu")
		(net 32)
	)
	(segment
		(start 107.650059 102.76752)
		(end 109.52506 102.76752)
		(width 0.185)
		(layer "B.Cu")
		(net 32)
	)
	(segment
		(start 133.875059 115.327276)
		(end 133.875059 111.085623)
		(width 0.185)
		(layer "B.Cu")
		(net 32)
	)
	(segment
		(start 109.61006 102.68252)
		(end 114.531956 102.68252)
		(width 0.185)
		(layer "B.Cu")
		(net 32)
	)
	(segment
		(start 135.255311 104.71667)
		(end 135.538153 104.71667)
		(width 0.185)
		(layer "B.Cu")
		(net 32)
	)
	(segment
		(start 133.875059 111.085623)
		(end 134.192884 110.767798)
		(width 0.185)
		(layer "B.Cu")
		(net 32)
	)
	(segment
		(start 134.192884 110.767798)
		(end 134.56058 110.767798)
		(width 0.185)
		(layer "B.Cu")
		(net 32)
	)
	(segment
		(start 134.210059 115.662276)
		(end 133.875059 115.327276)
		(width 0.185)
		(layer "B.Cu")
		(net 32)
	)
	(segment
		(start 117.001713 105.152277)
		(end 134.819704 105.152277)
		(width 0.185)
		(layer "B.Cu")
		(net 32)
	)
	(segment
		(start 114.531956 102.68252)
		(end 117.001713 105.152277)
		(width 0.185)
		(layer "B.Cu")
		(net 32)
	)
	(segment
		(start 109.52506 102.76752)
		(end 109.61006 102.68252)
		(width 0.185)
		(layer "B.Cu")
		(net 32)
	)
	(segment
		(start 134.819704 105.152277)
		(end 135.255311 104.71667)
		(width 0.185)
		(layer "B.Cu")
		(net 32)
	)
	(segment
		(start 134.210059 118.812277)
		(end 134.210059 115.662276)
		(width 0.185)
		(layer "B.Cu")
		(net 32)
	)
	(segment
		(start 134.525059 109.968931)
		(end 134.525059 104.98023)
		(width 0.185)
		(layer "F.Cu")
		(net 33)
	)
	(segment
		(start 134.525059 104.98023)
		(end 135.021965 104.483324)
		(width 0.185)
		(layer "F.Cu")
		(net 33)
	)
	(segment
		(start 134.327234 110.166756)
		(end 134.525059 109.968931)
		(width 0.185)
		(layer "F.Cu")
		(net 33)
	)
	(segment
		(start 135.021965 104.483324)
		(end 135.021965 104.200482)
		(width 0.185)
		(layer "F.Cu")
		(net 33)
	)
	(segment
		(start 133.959538 110.166756)
		(end 134.327234 110.166756)
		(width 0.185)
		(layer "F.Cu")
		(net 33)
	)
	(via
		(at 135.021965 104.200482)
		(size 0.55)
		(drill 0.25)
		(layers "F.Cu" "B.Cu")
		(net 33)
	)
	(via
		(at 133.959538 110.166756)
		(size 0.6)
		(drill 0.3)
		(layers "F.Cu" "B.Cu")
		(net 33)
	)
	(segment
		(start 117.138405 104.822277)
		(end 134.683012 104.822277)
		(width 0.185)
		(layer "B.Cu")
		(net 33)
	)
	(segment
		(start 133.210059 115.662276)
		(end 133.545059 115.327276)
		(width 0.185)
		(layer "B.Cu")
		(net 33)
	)
	(segment
		(start 107.650059 102.26752)
		(end 109.52506 102.26752)
		(width 0.185)
		(layer "B.Cu")
		(net 33)
	)
	(segment
		(start 133.545059 110.948931)
		(end 133.959538 110.534452)
		(width 0.185)
		(layer "B.Cu")
		(net 33)
	)
	(segment
		(start 135.021965 104.483324)
		(end 135.021965 104.200482)
		(width 0.185)
		(layer "B.Cu")
		(net 33)
	)
	(segment
		(start 133.959538 110.534452)
		(end 133.959538 110.166756)
		(width 0.185)
		(layer "B.Cu")
		(net 33)
	)
	(segment
		(start 109.52506 102.26752)
		(end 109.61006 102.35252)
		(width 0.185)
		(layer "B.Cu")
		(net 33)
	)
	(segment
		(start 133.545059 115.327276)
		(end 133.545059 110.948931)
		(width 0.185)
		(layer "B.Cu")
		(net 33)
	)
	(segment
		(start 109.61006 102.35252)
		(end 114.668648 102.35252)
		(width 0.185)
		(layer "B.Cu")
		(net 33)
	)
	(segment
		(start 114.668648 102.35252)
		(end 117.138405 104.822277)
		(width 0.185)
		(layer "B.Cu")
		(net 33)
	)
	(segment
		(start 134.683012 104.822277)
		(end 135.021965 104.483324)
		(width 0.185)
		(layer "B.Cu")
		(net 33)
	)
	(segment
		(start 133.210059 118.812277)
		(end 133.210059 115.662276)
		(width 0.185)
		(layer "B.Cu")
		(net 33)
	)
	(segment
		(start 130.345059 109.387277)
		(end 130.545058 109.187278)
		(width 0.185)
		(layer "F.Cu")
		(net 34)
	)
	(segment
		(start 131.335855 106.602275)
		(end 131.04006 106.602275)
		(width 0.185)
		(layer "F.Cu")
		(net 34)
	)
	(segment
		(start 130.545058 102.050231)
		(end 131.111965 101.483324)
		(width 0.185)
		(layer "F.Cu")
		(net 34)
	)
	(segment
		(start 130.545058 106.107273)
		(end 130.545058 102.050231)
		(width 0.185)
		(layer "F.Cu")
		(net 34)
	)
	(segment
		(start 130.545058 109.187278)
		(end 130.545058 107.427277)
		(width 0.185)
		(layer "F.Cu")
		(net 34)
	)
	(segment
		(start 131.111965 101.483324)
		(end 131.111965 101.200482)
		(width 0.185)
		(layer "F.Cu")
		(net 34)
	)
	(segment
		(start 131.04006 106.932275)
		(end 131.335855 106.932275)
		(width 0.185)
		(layer "F.Cu")
		(net 34)
	)
	(via
		(at 131.111965 101.200482)
		(size 0.55)
		(drill 0.25)
		(layers "F.Cu" "B.Cu")
		(net 34)
	)
	(via
		(at 130.345059 109.387277)
		(size 0.55)
		(drill 0.25)
		(layers "F.Cu" "B.Cu")
		(net 34)
	)
	(arc
		(start 131.500855 106.767275)
		(mid 131.452528 106.650602)
		(end 131.335855 106.602275)
		(width 0.185)
		(layer "F.Cu")
		(net 34)
	)
	(arc
		(start 131.04006 106.602275)
		(mid 130.690041 106.457292)
		(end 130.545058 106.107273)
		(width 0.185)
		(layer "F.Cu")
		(net 34)
	)
	(arc
		(start 130.545058 107.427277)
		(mid 130.690041 107.077258)
		(end 131.04006 106.932275)
		(width 0.185)
		(layer "F.Cu")
		(net 34)
	)
	(arc
		(start 131.335855 106.932275)
		(mid 131.452528 106.883948)
		(end 131.500855 106.767275)
		(width 0.185)
		(layer "F.Cu")
		(net 34)
	)
	(segment
		(start 130.210059 118.812277)
		(end 130.210059 115.662276)
		(width 0.185)
		(layer "B.Cu")
		(net 34)
	)
	(segment
		(start 107.650059 99.26752)
		(end 109.52506 99.26752)
		(width 0.185)
		(layer "B.Cu")
		(net 34)
	)
	(segment
		(start 130.545059 115.327276)
		(end 130.545058 109.587276)
		(width 0.185)
		(layer "B.Cu")
		(net 34)
	)
	(segment
		(start 131.111965 101.483324)
		(end 131.111965 101.200482)
		(width 0.185)
		(layer "B.Cu")
		(net 34)
	)
	(segment
		(start 130.783012 101.812277)
		(end 131.111965 101.483324)
		(width 0.185)
		(layer "B.Cu")
		(net 34)
	)
	(segment
		(start 109.61006 99.35252)
		(end 114.938648 99.35252)
		(width 0.185)
		(layer "B.Cu")
		(net 34)
	)
	(segment
		(start 117.398405 101.812277)
		(end 130.783012 101.812277)
		(width 0.185)
		(layer "B.Cu")
		(net 34)
	)
	(segment
		(start 130.545058 109.587276)
		(end 130.345059 109.387277)
		(width 0.185)
		(layer "B.Cu")
		(net 34)
	)
	(segment
		(start 114.938648 99.35252)
		(end 117.398405 101.812277)
		(width 0.185)
		(layer "B.Cu")
		(net 34)
	)
	(segment
		(start 130.210059 115.662276)
		(end 130.545059 115.327276)
		(width 0.185)
		(layer "B.Cu")
		(net 34)
	)
	(segment
		(start 109.52506 99.26752)
		(end 109.61006 99.35252)
		(width 0.185)
		(layer "B.Cu")
		(net 34)
	)
	(segment
		(start 131.345311 101.71667)
		(end 131.628153 101.71667)
		(width 0.185)
		(layer "F.Cu")
		(net 35)
	)
	(segment
		(start 131.335855 106.272273)
		(end 131.04006 106.272273)
		(width 0.185)
		(layer "F.Cu")
		(net 35)
	)
	(segment
		(start 130.87506 109.187278)
		(end 130.87506 107.427277)
		(width 0.185)
		(layer "F.Cu")
		(net 35)
	)
	(segment
		(start 131.075059 109.387277)
		(end 130.87506 109.187278)
		(width 0.185)
		(layer "F.Cu")
		(net 35)
	)
	(segment
		(start 130.87506 102.186921)
		(end 131.345311 101.71667)
		(width 0.185)
		(layer "F.Cu")
		(net 35)
	)
	(segment
		(start 131.04006 107.262277)
		(end 131.335855 107.262277)
		(width 0.185)
		(layer "F.Cu")
		(net 35)
	)
	(segment
		(start 130.87506 106.107273)
		(end 130.87506 102.186921)
		(width 0.185)
		(layer "F.Cu")
		(net 35)
	)
	(via
		(at 131.628153 101.71667)
		(size 0.55)
		(drill 0.25)
		(layers "F.Cu" "B.Cu")
		(net 35)
	)
	(via
		(at 131.075059 109.387277)
		(size 0.55)
		(drill 0.25)
		(layers "F.Cu" "B.Cu")
		(net 35)
	)
	(arc
		(start 131.04006 106.272273)
		(mid 130.923387 106.223946)
		(end 130.87506 106.107273)
		(width 0.185)
		(layer "F.Cu")
		(net 35)
	)
	(arc
		(start 131.830857 106.767275)
		(mid 131.685874 106.417256)
		(end 131.335855 106.272273)
		(width 0.185)
		(layer "F.Cu")
		(net 35)
	)
	(arc
		(start 130.87506 107.427277)
		(mid 130.923387 107.310604)
		(end 131.04006 107.262277)
		(width 0.185)
		(layer "F.Cu")
		(net 35)
	)
	(arc
		(start 131.335855 107.262277)
		(mid 131.685874 107.117294)
		(end 131.830857 106.767275)
		(width 0.185)
		(layer "F.Cu")
		(net 35)
	)
	(segment
		(start 130.919704 102.142277)
		(end 131.345311 101.71667)
		(width 0.185)
		(layer "B.Cu")
		(net 35)
	)
	(segment
		(start 107.650059 99.76752)
		(end 109.52506 99.76752)
		(width 0.185)
		(layer "B.Cu")
		(net 35)
	)
	(segment
		(start 114.801956 99.68252)
		(end 117.261713 102.142277)
		(width 0.185)
		(layer "B.Cu")
		(net 35)
	)
	(segment
		(start 131.345311 101.71667)
		(end 131.628153 101.71667)
		(width 0.185)
		(layer "B.Cu")
		(net 35)
	)
	(segment
		(start 109.61006 99.68252)
		(end 114.801956 99.68252)
		(width 0.185)
		(layer "B.Cu")
		(net 35)
	)
	(segment
		(start 109.52506 99.76752)
		(end 109.61006 99.68252)
		(width 0.185)
		(layer "B.Cu")
		(net 35)
	)
	(segment
		(start 131.210059 115.662276)
		(end 130.875059 115.327276)
		(width 0.185)
		(layer "B.Cu")
		(net 35)
	)
	(segment
		(start 130.87506 109.587276)
		(end 131.075059 109.387277)
		(width 0.185)
		(layer "B.Cu")
		(net 35)
	)
	(segment
		(start 131.210059 118.812277)
		(end 131.210059 115.662276)
		(width 0.185)
		(layer "B.Cu")
		(net 35)
	)
	(segment
		(start 130.875059 115.327276)
		(end 130.87506 109.587276)
		(width 0.185)
		(layer "B.Cu")
		(net 35)
	)
	(segment
		(start 117.261713 102.142277)
		(end 130.919704 102.142277)
		(width 0.185)
		(layer "B.Cu")
		(net 35)
	)
	(segment
		(start 132.875059 103.656922)
		(end 132.875059 104.576449)
		(width 0.185)
		(layer "F.Cu")
		(net 36)
	)
	(segment
		(start 133.210059 115.667276)
		(end 133.210059 118.817277)
		(width 0.185)
		(layer "F.Cu")
		(net 36)
	)
	(segment
		(start 132.875059 115.332276)
		(end 133.210059 115.667276)
		(width 0.185)
		(layer "F.Cu")
		(net 36)
	)
	(segment
		(start 133.438153 103.37667)
		(end 133.155311 103.37667)
		(width 0.185)
		(layer "F.Cu")
		(net 36)
	)
	(segment
		(start 132.875059 105.987277)
		(end 132.875059 106.036449)
		(width 0.185)
		(layer "F.Cu")
		(net 36)
	)
	(segment
		(start 133.215474 107.271863)
		(end 133.050473 107.271863)
		(width 0.185)
		(layer "F.Cu")
		(net 36)
	)
	(segment
		(start 133.050473 104.751863)
		(end 133.215474 104.751863)
		(width 0.185)
		(layer "F.Cu")
		(net 36)
	)
	(segment
		(start 133.720888 106.717277)
		(end 133.720888 106.766449)
		(width 0.185)
		(layer "F.Cu")
		(net 36)
	)
	(segment
		(start 133.215474 105.811863)
		(end 133.050473 105.811863)
		(width 0.185)
		(layer "F.Cu")
		(net 36)
	)
	(segment
		(start 133.050473 106.211863)
		(end 133.215474 106.211863)
		(width 0.185)
		(layer "F.Cu")
		(net 36)
	)
	(segment
		(start 133.155311 103.37667)
		(end 132.875059 103.656922)
		(width 0.185)
		(layer "F.Cu")
		(net 36)
	)
	(segment
		(start 132.875059 107.447277)
		(end 132.875059 115.332276)
		(width 0.185)
		(layer "F.Cu")
		(net 36)
	)
	(segment
		(start 133.720888 105.257277)
		(end 133.720888 105.306449)
		(width 0.185)
		(layer "F.Cu")
		(net 36)
	)
	(via
		(at 133.438153 103.37667)
		(size 0.55)
		(drill 0.25)
		(layers "F.Cu" "B.Cu")
		(net 36)
	)
	(arc
		(start 132.875059 104.576449)
		(mid 132.926437 104.700485)
		(end 133.050473 104.751863)
		(width 0.185)
		(layer "F.Cu")
		(net 36)
	)
	(arc
		(start 133.215474 106.211863)
		(mid 133.572856 106.359895)
		(end 133.720888 106.717277)
		(width 0.185)
		(layer "F.Cu")
		(net 36)
	)
	(arc
		(start 133.720888 106.766449)
		(mid 133.572856 107.123831)
		(end 133.215474 107.271863)
		(width 0.185)
		(layer "F.Cu")
		(net 36)
	)
	(arc
		(start 132.875059 106.036449)
		(mid 132.926437 106.160485)
		(end 133.050473 106.211863)
		(width 0.185)
		(layer "F.Cu")
		(net 36)
	)
	(arc
		(start 133.050473 107.271863)
		(mid 132.926437 107.323241)
		(end 132.875059 107.447277)
		(width 0.185)
		(layer "F.Cu")
		(net 36)
	)
	(arc
		(start 133.215474 104.751863)
		(mid 133.572856 104.899895)
		(end 133.720888 105.257277)
		(width 0.185)
		(layer "F.Cu")
		(net 36)
	)
	(arc
		(start 133.050473 105.811863)
		(mid 132.926437 105.863241)
		(end 132.875059 105.987277)
		(width 0.185)
		(layer "F.Cu")
		(net 36)
	)
	(arc
		(start 133.720888 105.306449)
		(mid 133.572856 105.663831)
		(end 133.215474 105.811863)
		(width 0.185)
		(layer "F.Cu")
		(net 36)
	)
	(segment
		(start 114.651956 101.18252)
		(end 117.261713 103.792277)
		(width 0.185)
		(layer "B.Cu")
		(net 36)
	)
	(segment
		(start 109.61006 101.18252)
		(end 114.651956 101.18252)
		(width 0.185)
		(layer "B.Cu")
		(net 36)
	)
	(segment
		(start 109.52506 101.26752)
		(end 109.61006 101.18252)
		(width 0.185)
		(layer "B.Cu")
		(net 36)
	)
	(segment
		(start 107.650059 101.26752)
		(end 109.52506 101.26752)
		(width 0.185)
		(layer "B.Cu")
		(net 36)
	)
	(segment
		(start 133.155311 103.37667)
		(end 133.438153 103.37667)
		(width 0.185)
		(layer "B.Cu")
		(net 36)
	)
	(segment
		(start 117.261713 103.792277)
		(end 132.739704 103.792277)
		(width 0.185)
		(layer "B.Cu")
		(net 36)
	)
	(segment
		(start 132.739704 103.792277)
		(end 133.155311 103.37667)
		(width 0.185)
		(layer "B.Cu")
		(net 36)
	)
	(segment
		(start 132.921965 103.143324)
		(end 132.545059 103.52023)
		(width 0.185)
		(layer "F.Cu")
		(net 37)
	)
	(segment
		(start 133.215474 105.481863)
		(end 133.050473 105.481863)
		(width 0.185)
		(layer "F.Cu")
		(net 37)
	)
	(segment
		(start 133.390888 105.257277)
		(end 133.390888 105.306449)
		(width 0.185)
		(layer "F.Cu")
		(net 37)
	)
	(segment
		(start 132.545059 103.52023)
		(end 132.545059 104.576449)
		(width 0.185)
		(layer "F.Cu")
		(net 37)
	)
	(segment
		(start 132.210059 115.667276)
		(end 132.210059 118.817277)
		(width 0.185)
		(layer "F.Cu")
		(net 37)
	)
	(segment
		(start 133.050473 105.081863)
		(end 133.215474 105.081863)
		(width 0.185)
		(layer "F.Cu")
		(net 37)
	)
	(segment
		(start 133.390888 106.717277)
		(end 133.390888 106.766449)
		(width 0.185)
		(layer "F.Cu")
		(net 37)
	)
	(segment
		(start 132.545059 107.447277)
		(end 132.545059 115.332276)
		(width 0.185)
		(layer "F.Cu")
		(net 37)
	)
	(segment
		(start 133.050473 106.541863)
		(end 133.215474 106.541863)
		(width 0.185)
		(layer "F.Cu")
		(net 37)
	)
	(segment
		(start 132.545059 105.987277)
		(end 132.545059 106.036449)
		(width 0.185)
		(layer "F.Cu")
		(net 37)
	)
	(segment
		(start 133.215474 106.941863)
		(end 133.050473 106.941863)
		(width 0.185)
		(layer "F.Cu")
		(net 37)
	)
	(segment
		(start 132.545059 115.332276)
		(end 132.210059 115.667276)
		(width 0.185)
		(layer "F.Cu")
		(net 37)
	)
	(segment
		(start 132.921965 102.860482)
		(end 132.921965 103.143324)
		(width 0.185)
		(layer "F.Cu")
		(net 37)
	)
	(via
		(at 132.921965 102.860482)
		(size 0.55)
		(drill 0.25)
		(layers "F.Cu" "B.Cu")
		(net 37)
	)
	(arc
		(start 133.050473 106.941863)
		(mid 132.693091 107.089895)
		(end 132.545059 107.447277)
		(width 0.185)
		(layer "F.Cu")
		(net 37)
	)
	(arc
		(start 132.545059 104.576449)
		(mid 132.693091 104.933831)
		(end 133.050473 105.081863)
		(width 0.185)
		(layer "F.Cu")
		(net 37)
	)
	(arc
		(start 133.390888 106.766449)
		(mid 133.33951 106.890485)
		(end 133.215474 106.941863)
		(width 0.185)
		(layer "F.Cu")
		(net 37)
	)
	(arc
		(start 133.390888 105.306449)
		(mid 133.33951 105.430485)
		(end 133.215474 105.481863)
		(width 0.185)
		(layer "F.Cu")
		(net 37)
	)
	(arc
		(start 133.215474 105.081863)
		(mid 133.33951 105.133241)
		(end 133.390888 105.257277)
		(width 0.185)
		(layer "F.Cu")
		(net 37)
	)
	(arc
		(start 132.545059 106.036449)
		(mid 132.693091 106.393831)
		(end 133.050473 106.541863)
		(width 0.185)
		(layer "F.Cu")
		(net 37)
	)
	(arc
		(start 133.215474 106.541863)
		(mid 133.33951 106.593241)
		(end 133.390888 106.717277)
		(width 0.185)
		(layer "F.Cu")
		(net 37)
	)
	(arc
		(start 133.050473 105.481863)
		(mid 132.693091 105.629895)
		(end 132.545059 105.987277)
		(width 0.185)
		(layer "F.Cu")
		(net 37)
	)
	(segment
		(start 107.650059 100.76752)
		(end 109.52506 100.76752)
		(width 0.185)
		(layer "B.Cu")
		(net 37)
	)
	(segment
		(start 132.603012 103.462277)
		(end 132.921965 103.143324)
		(width 0.185)
		(layer "B.Cu")
		(net 37)
	)
	(segment
		(start 109.52506 100.76752)
		(end 109.61006 100.85252)
		(width 0.185)
		(layer "B.Cu")
		(net 37)
	)
	(segment
		(start 114.788648 100.85252)
		(end 117.398405 103.462277)
		(width 0.185)
		(layer "B.Cu")
		(net 37)
	)
	(segment
		(start 132.921965 103.143324)
		(end 132.921965 102.860482)
		(width 0.185)
		(layer "B.Cu")
		(net 37)
	)
	(segment
		(start 117.398405 103.462277)
		(end 132.603012 103.462277)
		(width 0.185)
		(layer "B.Cu")
		(net 37)
	)
	(segment
		(start 109.61006 100.85252)
		(end 114.788648 100.85252)
		(width 0.185)
		(layer "B.Cu")
		(net 37)
	)
	(segment
		(start 125.345059 109.447277)
		(end 125.545058 109.247278)
		(width 0.185)
		(layer "F.Cu")
		(net 38)
	)
	(segment
		(start 125.545058 103.197265)
		(end 125.545058 98.880231)
		(width 0.185)
		(layer "F.Cu")
		(net 38)
	)
	(segment
		(start 126.04006 106.332275)
		(end 126.26005 106.332275)
		(width 0.185)
		(layer "F.Cu")
		(net 38)
	)
	(segment
		(start 126.04006 105.342271)
		(end 126.26005 105.342271)
		(width 0.185)
		(layer "F.Cu")
		(net 38)
	)
	(segment
		(start 126.04006 106.662275)
		(end 126.26005 106.662275)
		(width 0.185)
		(layer "F.Cu")
		(net 38)
	)
	(segment
		(start 126.04006 104.022267)
		(end 126.260053 104.022267)
		(width 0.185)
		(layer "F.Cu")
		(net 38)
	)
	(segment
		(start 125.545058 98.880231)
		(end 125.981965 98.443324)
		(width 0.185)
		(layer "F.Cu")
		(net 38)
	)
	(segment
		(start 125.981965 98.443324)
		(end 125.981965 98.160482)
		(width 0.185)
		(layer "F.Cu")
		(net 38)
	)
	(segment
		(start 125.545058 109.247278)
		(end 125.545058 107.157277)
		(width 0.185)
		(layer "F.Cu")
		(net 38)
	)
	(segment
		(start 126.260053 103.692267)
		(end 126.04006 103.692267)
		(width 0.185)
		(layer "F.Cu")
		(net 38)
	)
	(segment
		(start 126.26005 105.012271)
		(end 126.04006 105.012271)
		(width 0.185)
		(layer "F.Cu")
		(net 38)
	)
	(via
		(at 125.981965 98.160482)
		(size 0.55)
		(drill 0.25)
		(layers "F.Cu" "B.Cu")
		(net 38)
	)
	(via
		(at 125.345059 109.447277)
		(size 0.55)
		(drill 0.25)
		(layers "F.Cu" "B.Cu")
		(net 38)
	)
	(arc
		(start 125.545058 107.157277)
		(mid 125.690041 106.807258)
		(end 126.04006 106.662275)
		(width 0.185)
		(layer "F.Cu")
		(net 38)
	)
	(arc
		(start 126.26005 105.342271)
		(mid 126.376723 105.293944)
		(end 126.42505 105.177271)
		(width 0.185)
		(layer "F.Cu")
		(net 38)
	)
	(arc
		(start 126.04006 103.692267)
		(mid 125.690041 103.547284)
		(end 125.545058 103.197265)
		(width 0.185)
		(layer "F.Cu")
		(net 38)
	)
	(arc
		(start 126.42505 105.177271)
		(mid 126.376723 105.060598)
		(end 126.26005 105.012271)
		(width 0.185)
		(layer "F.Cu")
		(net 38)
	)
	(arc
		(start 126.04006 106.332275)
		(mid 125.690041 106.187292)
		(end 125.545058 105.837273)
		(width 0.185)
		(layer "F.Cu")
		(net 38)
	)
	(arc
		(start 126.04006 105.012271)
		(mid 125.690041 104.867288)
		(end 125.545058 104.517269)
		(width 0.185)
		(layer "F.Cu")
		(net 38)
	)
	(arc
		(start 126.260053 104.022267)
		(mid 126.376726 103.97394)
		(end 126.425053 103.857267)
		(width 0.185)
		(layer "F.Cu")
		(net 38)
	)
	(arc
		(start 126.425053 103.857267)
		(mid 126.376726 103.740594)
		(end 126.260053 103.692267)
		(width 0.185)
		(layer "F.Cu")
		(net 38)
	)
	(arc
		(start 126.26005 106.662275)
		(mid 126.376723 106.613948)
		(end 126.42505 106.497275)
		(width 0.185)
		(layer "F.Cu")
		(net 38)
	)
	(arc
		(start 126.42505 106.497275)
		(mid 126.376723 106.380602)
		(end 126.26005 106.332275)
		(width 0.185)
		(layer "F.Cu")
		(net 38)
	)
	(arc
		(start 125.545058 104.517269)
		(mid 125.690041 104.16725)
		(end 126.04006 104.022267)
		(width 0.185)
		(layer "F.Cu")
		(net 38)
	)
	(arc
		(start 125.545058 105.837273)
		(mid 125.690041 105.487254)
		(end 126.04006 105.342271)
		(width 0.185)
		(layer "F.Cu")
		(net 38)
	)
	(segment
		(start 125.545059 115.327276)
		(end 125.545058 109.647276)
		(width 0.185)
		(layer "B.Cu")
		(net 38)
	)
	(segment
		(start 117.568405 98.682277)
		(end 125.743012 98.682277)
		(width 0.185)
		(layer "B.Cu")
		(net 38)
	)
	(segment
		(start 125.743012 98.682277)
		(end 125.981965 98.443324)
		(width 0.185)
		(layer "B.Cu")
		(net 38)
	)
	(segment
		(start 125.981965 98.443324)
		(end 125.981965 98.160482)
		(width 0.185)
		(layer "B.Cu")
		(net 38)
	)
	(segment
		(start 115.238648 96.35252)
		(end 117.568405 98.682277)
		(width 0.185)
		(layer "B.Cu")
		(net 38)
	)
	(segment
		(start 125.210059 115.662276)
		(end 125.545059 115.327276)
		(width 0.185)
		(layer "B.Cu")
		(net 38)
	)
	(segment
		(start 125.210059 118.812277)
		(end 125.210059 115.662276)
		(width 0.185)
		(layer "B.Cu")
		(net 38)
	)
	(segment
		(start 109.52506 96.26752)
		(end 109.61006 96.35252)
		(width 0.185)
		(layer "B.Cu")
		(net 38)
	)
	(segment
		(start 125.545058 109.647276)
		(end 125.345059 109.447277)
		(width 0.185)
		(layer "B.Cu")
		(net 38)
	)
	(segment
		(start 109.61006 96.35252)
		(end 115.238648 96.35252)
		(width 0.185)
		(layer "B.Cu")
		(net 38)
	)
	(segment
		(start 107.650059 96.26752)
		(end 109.52506 96.26752)
		(width 0.185)
		(layer "B.Cu")
		(net 38)
	)
	(segment
		(start 125.87506 99.016921)
		(end 126.215311 98.67667)
		(width 0.185)
		(layer "F.Cu")
		(net 39)
	)
	(segment
		(start 126.04006 106.002273)
		(end 126.26005 106.002273)
		(width 0.185)
		(layer "F.Cu")
		(net 39)
	)
	(segment
		(start 125.87506 103.197265)
		(end 125.87506 99.016921)
		(width 0.185)
		(layer "F.Cu")
		(net 39)
	)
	(segment
		(start 126.04006 106.992277)
		(end 126.26005 106.992277)
		(width 0.185)
		(layer "F.Cu")
		(net 39)
	)
	(segment
		(start 126.04006 105.672273)
		(end 126.26005 105.672273)
		(width 0.185)
		(layer "F.Cu")
		(net 39)
	)
	(segment
		(start 126.04006 104.352269)
		(end 126.260053 104.352269)
		(width 0.185)
		(layer "F.Cu")
		(net 39)
	)
	(segment
		(start 126.26005 104.682269)
		(end 126.04006 104.682269)
		(width 0.185)
		(layer "F.Cu")
		(net 39)
	)
	(segment
		(start 126.075059 109.447277)
		(end 125.87506 109.247278)
		(width 0.185)
		(layer "F.Cu")
		(net 39)
	)
	(segment
		(start 125.87506 109.247278)
		(end 125.87506 107.157277)
		(width 0.185)
		(layer "F.Cu")
		(net 39)
	)
	(segment
		(start 126.260053 103.362265)
		(end 126.04006 103.362265)
		(width 0.185)
		(layer "F.Cu")
		(net 39)
	)
	(segment
		(start 126.215311 98.67667)
		(end 126.498153 98.67667)
		(width 0.185)
		(layer "F.Cu")
		(net 39)
	)
	(via
		(at 126.075059 109.447277)
		(size 0.55)
		(drill 0.25)
		(layers "F.Cu" "B.Cu")
		(net 39)
	)
	(via
		(at 126.498153 98.67667)
		(size 0.55)
		(drill 0.25)
		(layers "F.Cu" "B.Cu")
		(net 39)
	)
	(arc
		(start 125.87506 105.837273)
		(mid 125.923387 105.7206)
		(end 126.04006 105.672273)
		(width 0.185)
		(layer "F.Cu")
		(net 39)
	)
	(arc
		(start 126.26005 106.992277)
		(mid 126.610069 106.847294)
		(end 126.755052 106.497275)
		(width 0.185)
		(layer "F.Cu")
		(net 39)
	)
	(arc
		(start 126.04006 104.682269)
		(mid 125.923387 104.633942)
		(end 125.87506 104.517269)
		(width 0.185)
		(layer "F.Cu")
		(net 39)
	)
	(arc
		(start 125.87506 104.517269)
		(mid 125.923387 104.400596)
		(end 126.04006 104.352269)
		(width 0.185)
		(layer "F.Cu")
		(net 39)
	)
	(arc
		(start 126.260053 104.352269)
		(mid 126.610072 104.207286)
		(end 126.755055 103.857267)
		(width 0.185)
		(layer "F.Cu")
		(net 39)
	)
	(arc
		(start 126.755052 105.177271)
		(mid 126.610069 104.827252)
		(end 126.26005 104.682269)
		(width 0.185)
		(layer "F.Cu")
		(net 39)
	)
	(arc
		(start 126.755055 103.857267)
		(mid 126.610072 103.507248)
		(end 126.260053 103.362265)
		(width 0.185)
		(layer "F.Cu")
		(net 39)
	)
	(arc
		(start 126.04006 106.002273)
		(mid 125.923387 105.953946)
		(end 125.87506 105.837273)
		(width 0.185)
		(layer "F.Cu")
		(net 39)
	)
	(arc
		(start 125.87506 107.157277)
		(mid 125.923387 107.040604)
		(end 126.04006 106.992277)
		(width 0.185)
		(layer "F.Cu")
		(net 39)
	)
	(arc
		(start 126.26005 105.672273)
		(mid 126.610069 105.52729)
		(end 126.755052 105.177271)
		(width 0.185)
		(layer "F.Cu")
		(net 39)
	)
	(arc
		(start 126.755052 106.497275)
		(mid 126.610069 106.147256)
		(end 126.26005 106.002273)
		(width 0.185)
		(layer "F.Cu")
		(net 39)
	)
	(arc
		(start 126.04006 103.362265)
		(mid 125.923387 103.313938)
		(end 125.87506 103.197265)
		(width 0.185)
		(layer "F.Cu")
		(net 39)
	)
	(segment
		(start 117.431713 99.012277)
		(end 125.879704 99.012277)
		(width 0.185)
		(layer "B.Cu")
		(net 39)
	)
	(segment
		(start 125.875059 115.327276)
		(end 125.87506 109.647276)
		(width 0.185)
		(layer "B.Cu")
		(net 39)
	)
	(segment
		(start 126.210059 118.812277)
		(end 126.210059 115.662276)
		(width 0.185)
		(layer "B.Cu")
		(net 39)
	)
	(segment
		(start 107.650059 96.76752)
		(end 109.52506 96.76752)
		(width 0.185)
		(layer "B.Cu")
		(net 39)
	)
	(segment
		(start 125.87506 109.647276)
		(end 126.075059 109.447277)
		(width 0.185)
		(layer "B.Cu")
		(net 39)
	)
	(segment
		(start 109.52506 96.76752)
		(end 109.61006 96.68252)
		(width 0.185)
		(layer "B.Cu")
		(net 39)
	)
	(segment
		(start 125.879704 99.012277)
		(end 126.215311 98.67667)
		(width 0.185)
		(layer "B.Cu")
		(net 39)
	)
	(segment
		(start 126.215311 98.67667)
		(end 126.498153 98.67667)
		(width 0.185)
		(layer "B.Cu")
		(net 39)
	)
	(segment
		(start 115.101956 96.68252)
		(end 117.431713 99.012277)
		(width 0.185)
		(layer "B.Cu")
		(net 39)
	)
	(segment
		(start 126.210059 115.662276)
		(end 125.875059 115.327276)
		(width 0.185)
		(layer "B.Cu")
		(net 39)
	)
	(segment
		(start 109.61006 96.68252)
		(end 115.101956 96.68252)
		(width 0.185)
		(layer "B.Cu")
		(net 39)
	)
	(segment
		(start 127.875059 115.332276)
		(end 127.875059 107.437277)
		(width 0.185)
		(layer "F.Cu")
		(net 40)
	)
	(segment
		(start 127.875059 100.876922)
		(end 128.565311 100.18667)
		(width 0.185)
		(layer "F.Cu")
		(net 40)
	)
	(segment
		(start 127.875059 103.477277)
		(end 127.875059 100.876922)
		(width 0.185)
		(layer "F.Cu")
		(net 40)
	)
	(segment
		(start 128.565311 100.18667)
		(end 128.848153 100.18667)
		(width 0.185)
		(layer "F.Cu")
		(net 40)
	)
	(segment
		(start 128.040059 104.632277)
		(end 128.251952 104.632277)
		(width 0.185)
		(layer "F.Cu")
		(net 40)
	)
	(segment
		(start 128.210059 118.817277)
		(end 128.210059 115.667276)
		(width 0.185)
		(layer "F.Cu")
		(net 40)
	)
	(segment
		(start 128.040059 107.272277)
		(end 128.251967 107.272277)
		(width 0.185)
		(layer "F.Cu")
		(net 40)
	)
	(segment
		(start 128.040059 105.952277)
		(end 128.251952 105.952277)
		(width 0.185)
		(layer "F.Cu")
		(net 40)
	)
	(segment
		(start 128.210059 115.667276)
		(end 127.875059 115.332276)
		(width 0.185)
		(layer "F.Cu")
		(net 40)
	)
	(segment
		(start 128.251967 106.282277)
		(end 128.040059 106.282277)
		(width 0.185)
		(layer "F.Cu")
		(net 40)
	)
	(segment
		(start 128.251952 104.962277)
		(end 128.040059 104.962277)
		(width 0.185)
		(layer "F.Cu")
		(net 40)
	)
	(segment
		(start 128.251952 103.642277)
		(end 128.040059 103.642277)
		(width 0.185)
		(layer "F.Cu")
		(net 40)
	)
	(via
		(at 128.848153 100.18667)
		(size 0.55)
		(drill 0.25)
		(layers "F.Cu" "B.Cu")
		(net 40)
	)
	(arc
		(start 128.746952 105.457277)
		(mid 128.60197 105.107259)
		(end 128.251952 104.962277)
		(width 0.185)
		(layer "F.Cu")
		(net 40)
	)
	(arc
		(start 128.040059 104.962277)
		(mid 127.923386 104.91395)
		(end 127.875059 104.797277)
		(width 0.185)
		(layer "F.Cu")
		(net 40)
	)
	(arc
		(start 128.251967 107.272277)
		(mid 128.601985 107.127295)
		(end 128.746967 106.777277)
		(width 0.185)
		(layer "F.Cu")
		(net 40)
	)
	(arc
		(start 127.875059 104.797277)
		(mid 127.923386 104.680604)
		(end 128.040059 104.632277)
		(width 0.185)
		(layer "F.Cu")
		(net 40)
	)
	(arc
		(start 128.251952 105.952277)
		(mid 128.60197 105.807295)
		(end 128.746952 105.457277)
		(width 0.185)
		(layer "F.Cu")
		(net 40)
	)
	(arc
		(start 128.746967 106.777277)
		(mid 128.601985 106.427259)
		(end 128.251967 106.282277)
		(width 0.185)
		(layer "F.Cu")
		(net 40)
	)
	(arc
		(start 128.251952 104.632277)
		(mid 128.60197 104.487295)
		(end 128.746952 104.137277)
		(width 0.185)
		(layer "F.Cu")
		(net 40)
	)
	(arc
		(start 127.875059 106.117277)
		(mid 127.923386 106.000604)
		(end 128.040059 105.952277)
		(width 0.185)
		(layer "F.Cu")
		(net 40)
	)
	(arc
		(start 128.040059 106.282277)
		(mid 127.923386 106.23395)
		(end 127.875059 106.117277)
		(width 0.185)
		(layer "F.Cu")
		(net 40)
	)
	(arc
		(start 128.040059 103.642277)
		(mid 127.923386 103.59395)
		(end 127.875059 103.477277)
		(width 0.185)
		(layer "F.Cu")
		(net 40)
	)
	(arc
		(start 128.746952 104.137277)
		(mid 128.60197 103.787259)
		(end 128.251952 103.642277)
		(width 0.185)
		(layer "F.Cu")
		(net 40)
	)
	(arc
		(start 127.875059 107.437277)
		(mid 127.923386 107.320604)
		(end 128.040059 107.272277)
		(width 0.185)
		(layer "F.Cu")
		(net 40)
	)
	(segment
		(start 128.565311 100.18667)
		(end 128.848153 100.18667)
		(width 0.185)
		(layer "B.Cu")
		(net 40)
	)
	(segment
		(start 128.159704 100.592277)
		(end 128.565311 100.18667)
		(width 0.185)
		(layer "B.Cu")
		(net 40)
	)
	(segment
		(start 117.371713 100.592277)
		(end 128.159704 100.592277)
		(width 0.185)
		(layer "B.Cu")
		(net 40)
	)
	(segment
		(start 114.961956 98.18252)
		(end 117.371713 100.592277)
		(width 0.185)
		(layer "B.Cu")
		(net 40)
	)
	(segment
		(start 109.52506 98.26752)
		(end 109.61006 98.18252)
		(width 0.185)
		(layer "B.Cu")
		(net 40)
	)
	(segment
		(start 107.650059 98.26752)
		(end 109.52506 98.26752)
		(width 0.185)
		(layer "B.Cu")
		(net 40)
	)
	(segment
		(start 109.61006 98.18252)
		(end 114.961956 98.18252)
		(width 0.185)
		(layer "B.Cu")
		(net 40)
	)
	(segment
		(start 128.251952 103.972277)
		(end 128.040059 103.972277)
		(width 0.185)
		(layer "F.Cu")
		(net 41)
	)
	(segment
		(start 127.545059 103.477277)
		(end 127.545059 100.74023)
		(width 0.185)
		(layer "F.Cu")
		(net 41)
	)
	(segment
		(start 128.331965 99.953324)
		(end 128.331965 99.670482)
		(width 0.185)
		(layer "F.Cu")
		(net 41)
	)
	(segment
		(start 128.251967 106.612277)
		(end 128.040059 106.612277)
		(width 0.185)
		(layer "F.Cu")
		(net 41)
	)
	(segment
		(start 128.040059 105.622277)
		(end 128.251952 105.622277)
		(width 0.185)
		(layer "F.Cu")
		(net 41)
	)
	(segment
		(start 128.040059 106.942277)
		(end 128.251967 106.942277)
		(width 0.185)
		(layer "F.Cu")
		(net 41)
	)
	(segment
		(start 127.545059 100.74023)
		(end 128.331965 99.953324)
		(width 0.185)
		(layer "F.Cu")
		(net 41)
	)
	(segment
		(start 128.251952 105.292277)
		(end 128.040059 105.292277)
		(width 0.185)
		(layer "F.Cu")
		(net 41)
	)
	(segment
		(start 127.210059 115.667276)
		(end 127.545059 115.332276)
		(width 0.185)
		(layer "F.Cu")
		(net 41)
	)
	(segment
		(start 128.040059 104.302277)
		(end 128.251952 104.302277)
		(width 0.185)
		(layer "F.Cu")
		(net 41)
	)
	(segment
		(start 127.545059 115.332276)
		(end 127.545059 107.437277)
		(width 0.185)
		(layer "F.Cu")
		(net 41)
	)
	(segment
		(start 127.210059 118.817277)
		(end 127.210059 115.667276)
		(width 0.185)
		(layer "F.Cu")
		(net 41)
	)
	(via
		(at 128.331965 99.670482)
		(size 0.55)
		(drill 0.25)
		(layers "F.Cu" "B.Cu")
		(net 41)
	)
	(arc
		(start 128.251952 105.622277)
		(mid 128.368625 105.57395)
		(end 128.416952 105.457277)
		(width 0.185)
		(layer "F.Cu")
		(net 41)
	)
	(arc
		(start 128.040059 105.292277)
		(mid 127.690041 105.147295)
		(end 127.545059 104.797277)
		(width 0.185)
		(layer "F.Cu")
		(net 41)
	)
	(arc
		(start 128.251967 106.942277)
		(mid 128.36864 106.89395)
		(end 128.416967 106.777277)
		(width 0.185)
		(layer "F.Cu")
		(net 41)
	)
	(arc
		(start 127.545059 107.437277)
		(mid 127.690041 107.087259)
		(end 128.040059 106.942277)
		(width 0.185)
		(layer "F.Cu")
		(net 41)
	)
	(arc
		(start 128.416967 106.777277)
		(mid 128.36864 106.660604)
		(end 128.251967 106.612277)
		(width 0.185)
		(layer "F.Cu")
		(net 41)
	)
	(arc
		(start 128.251952 104.302277)
		(mid 128.368625 104.25395)
		(end 128.416952 104.137277)
		(width 0.185)
		(layer "F.Cu")
		(net 41)
	)
	(arc
		(start 127.545059 104.797277)
		(mid 127.690041 104.447259)
		(end 128.040059 104.302277)
		(width 0.185)
		(layer "F.Cu")
		(net 41)
	)
	(arc
		(start 128.040059 103.972277)
		(mid 127.690041 103.827295)
		(end 127.545059 103.477277)
		(width 0.185)
		(layer "F.Cu")
		(net 41)
	)
	(arc
		(start 128.416952 105.457277)
		(mid 128.368625 105.340604)
		(end 128.251952 105.292277)
		(width 0.185)
		(layer "F.Cu")
		(net 41)
	)
	(arc
		(start 128.040059 106.612277)
		(mid 127.690041 106.467295)
		(end 127.545059 106.117277)
		(width 0.185)
		(layer "F.Cu")
		(net 41)
	)
	(arc
		(start 127.545059 106.117277)
		(mid 127.690041 105.767259)
		(end 128.040059 105.622277)
		(width 0.185)
		(layer "F.Cu")
		(net 41)
	)
	(arc
		(start 128.416952 104.137277)
		(mid 128.368625 104.020604)
		(end 128.251952 103.972277)
		(width 0.185)
		(layer "F.Cu")
		(net 41)
	)
	(segment
		(start 117.508405 100.262277)
		(end 128.023012 100.262277)
		(width 0.185)
		(layer "B.Cu")
		(net 41)
	)
	(segment
		(start 115.098648 97.85252)
		(end 117.508405 100.262277)
		(width 0.185)
		(layer "B.Cu")
		(net 41)
	)
	(segment
		(start 109.52506 97.76752)
		(end 109.61006 97.85252)
		(width 0.185)
		(layer "B.Cu")
		(net 41)
	)
	(segment
		(start 128.023012 100.262277)
		(end 128.331965 99.953324)
		(width 0.185)
		(layer "B.Cu")
		(net 41)
	)
	(segment
		(start 107.650059 97.76752)
		(end 109.52506 97.76752)
		(width 0.185)
		(layer "B.Cu")
		(net 41)
	)
	(segment
		(start 128.331965 99.953324)
		(end 128.331965 99.670482)
		(width 0.185)
		(layer "B.Cu")
		(net 41)
	)
	(segment
		(start 109.61006 97.85252)
		(end 115.098648 97.85252)
		(width 0.185)
		(layer "B.Cu")
		(net 41)
	)
	(segment
		(start 122.215413 104.122267)
		(end 122.04006 104.122267)
		(width 0.185)
		(layer "F.Cu")
		(net 42)
	)
	(segment
		(start 122.131965 95.483324)
		(end 121.545058 96.070231)
		(width 0.185)
		(layer "F.Cu")
		(net 42)
	)
	(segment
		(start 122.04006 102.472263)
		(end 122.215392 102.472263)
		(width 0.185)
		(layer "F.Cu")
		(net 42)
	)
	(segment
		(start 122.04006 105.112271)
		(end 122.215392 105.112271)
		(width 0.185)
		(layer "F.Cu")
		(net 42)
	)
	(segment
		(start 122.131965 95.200482)
		(end 122.131965 95.483324)
		(width 0.185)
		(layer "F.Cu")
		(net 42)
	)
	(segment
		(start 121.545058 107.257277)
		(end 121.545058 109.167278)
		(width 0.185)
		(layer "F.Cu")
		(net 42)
	)
	(segment
		(start 122.215392 102.802263)
		(end 122.04006 102.802263)
		(width 0.185)
		(layer "F.Cu")
		(net 42)
	)
	(segment
		(start 122.215413 106.762275)
		(end 122.04006 106.762275)
		(width 0.185)
		(layer "F.Cu")
		(net 42)
	)
	(segment
		(start 122.04006 106.432275)
		(end 122.215413 106.432275)
		(width 0.185)
		(layer "F.Cu")
		(net 42)
	)
	(segment
		(start 122.04006 103.792267)
		(end 122.215413 103.792267)
		(width 0.185)
		(layer "F.Cu")
		(net 42)
	)
	(segment
		(start 122.215392 105.442271)
		(end 122.04006 105.442271)
		(width 0.185)
		(layer "F.Cu")
		(net 42)
	)
	(segment
		(start 121.545058 96.070231)
		(end 121.545058 101.977261)
		(width 0.185)
		(layer "F.Cu")
		(net 42)
	)
	(segment
		(start 121.545058 109.167278)
		(end 121.345059 109.367277)
		(width 0.185)
		(layer "F.Cu")
		(net 42)
	)
	(via
		(at 121.345059 109.367277)
		(size 0.55)
		(drill 0.25)
		(layers "F.Cu" "B.Cu")
		(net 42)
	)
	(via
		(at 122.131965 95.200482)
		(size 0.55)
		(drill 0.25)
		(layers "F.Cu" "B.Cu")
		(net 42)
	)
	(arc
		(start 122.380413 106.597275)
		(mid 122.332086 106.713948)
		(end 122.215413 106.762275)
		(width 0.185)
		(layer "F.Cu")
		(net 42)
	)
	(arc
		(start 121.545058 103.297265)
		(mid 121.690041 103.647284)
		(end 122.04006 103.792267)
		(width 0.185)
		(layer "F.Cu")
		(net 42)
	)
	(arc
		(start 122.380392 102.637263)
		(mid 122.332065 102.753936)
		(end 122.215392 102.802263)
		(width 0.185)
		(layer "F.Cu")
		(net 42)
	)
	(arc
		(start 121.545058 105.937273)
		(mid 121.690041 106.287292)
		(end 122.04006 106.432275)
		(width 0.185)
		(layer "F.Cu")
		(net 42)
	)
	(arc
		(start 122.04006 105.442271)
		(mid 121.690041 105.587254)
		(end 121.545058 105.937273)
		(width 0.185)
		(layer "F.Cu")
		(net 42)
	)
	(arc
		(start 121.545058 101.977261)
		(mid 121.690041 102.32728)
		(end 122.04006 102.472263)
		(width 0.185)
		(layer "F.Cu")
		(net 42)
	)
	(arc
		(start 122.04006 106.762275)
		(mid 121.690041 106.907258)
		(end 121.545058 107.257277)
		(width 0.185)
		(layer "F.Cu")
		(net 42)
	)
	(arc
		(start 122.04006 102.802263)
		(mid 121.690041 102.947246)
		(end 121.545058 103.297265)
		(width 0.185)
		(layer "F.Cu")
		(net 42)
	)
	(arc
		(start 122.215413 106.432275)
		(mid 122.332086 106.480602)
		(end 122.380413 106.597275)
		(width 0.185)
		(layer "F.Cu")
		(net 42)
	)
	(arc
		(start 122.04006 104.122267)
		(mid 121.690041 104.26725)
		(end 121.545058 104.617269)
		(width 0.185)
		(layer "F.Cu")
		(net 42)
	)
	(arc
		(start 122.215392 102.472263)
		(mid 122.332065 102.52059)
		(end 122.380392 102.637263)
		(width 0.185)
		(layer "F.Cu")
		(net 42)
	)
	(arc
		(start 122.215392 105.112271)
		(mid 122.332065 105.160598)
		(end 122.380392 105.277271)
		(width 0.185)
		(layer "F.Cu")
		(net 42)
	)
	(arc
		(start 122.380413 103.957267)
		(mid 122.332086 104.07394)
		(end 122.215413 104.122267)
		(width 0.185)
		(layer "F.Cu")
		(net 42)
	)
	(arc
		(start 121.545058 104.617269)
		(mid 121.690041 104.967288)
		(end 122.04006 105.112271)
		(width 0.185)
		(layer "F.Cu")
		(net 42)
	)
	(arc
		(start 122.215413 103.792267)
		(mid 122.332086 103.840594)
		(end 122.380413 103.957267)
		(width 0.185)
		(layer "F.Cu")
		(net 42)
	)
	(arc
		(start 122.380392 105.277271)
		(mid 122.332065 105.393944)
		(end 122.215392 105.442271)
		(width 0.185)
		(layer "F.Cu")
		(net 42)
	)
	(segment
		(start 121.210059 115.662276)
		(end 121.210059 118.812277)
		(width 0.185)
		(layer "B.Cu")
		(net 42)
	)
	(segment
		(start 121.545059 115.327276)
		(end 121.210059 115.662276)
		(width 0.185)
		(layer "B.Cu")
		(net 42)
	)
	(segment
		(start 121.923012 95.692277)
		(end 118.008405 95.692277)
		(width 0.185)
		(layer "B.Cu")
		(net 42)
	)
	(segment
		(start 121.345059 109.367277)
		(end 121.545059 109.567277)
		(width 0.185)
		(layer "B.Cu")
		(net 42)
	)
	(segment
		(start 118.008405 95.692277)
		(end 115.668648 93.35252)
		(width 0.185)
		(layer "B.Cu")
		(net 42)
	)
	(segment
		(start 115.668648 93.35252)
		(end 109.61006 93.35252)
		(width 0.185)
		(layer "B.Cu")
		(net 42)
	)
	(segment
		(start 122.131965 95.483324)
		(end 121.923012 95.692277)
		(width 0.185)
		(layer "B.Cu")
		(net 42)
	)
	(segment
		(start 109.52506 93.26752)
		(end 107.650059 93.26752)
		(width 0.185)
		(layer "B.Cu")
		(net 42)
	)
	(segment
		(start 109.61006 93.35252)
		(end 109.52506 93.26752)
		(width 0.185)
		(layer "B.Cu")
		(net 42)
	)
	(segment
		(start 122.131965 95.200482)
		(end 122.131965 95.483324)
		(width 0.185)
		(layer "B.Cu")
		(net 42)
	)
	(segment
		(start 121.545059 109.567277)
		(end 121.545059 115.327276)
		(width 0.185)
		(layer "B.Cu")
		(net 42)
	)
	(segment
		(start 121.87506 96.206921)
		(end 121.87506 101.977261)
		(width 0.185)
		(layer "F.Cu")
		(net 43)
	)
	(segment
		(start 122.215392 105.772273)
		(end 122.04006 105.772273)
		(width 0.185)
		(layer "F.Cu")
		(net 43)
	)
	(segment
		(start 122.04006 106.102273)
		(end 122.215413 106.102273)
		(width 0.185)
		(layer "F.Cu")
		(net 43)
	)
	(segment
		(start 122.04006 104.782269)
		(end 122.215392 104.782269)
		(width 0.185)
		(layer "F.Cu")
		(net 43)
	)
	(segment
		(start 122.365311 95.71667)
		(end 121.87506 96.206921)
		(width 0.185)
		(layer "F.Cu")
		(net 43)
	)
	(segment
		(start 122.04006 103.462265)
		(end 122.215413 103.462265)
		(width 0.185)
		(layer "F.Cu")
		(net 43)
	)
	(segment
		(start 121.87506 107.257277)
		(end 121.87506 109.167278)
		(width 0.185)
		(layer "F.Cu")
		(net 43)
	)
	(segment
		(start 122.215413 107.092277)
		(end 122.04006 107.092277)
		(width 0.185)
		(layer "F.Cu")
		(net 43)
	)
	(segment
		(start 121.87506 109.167278)
		(end 122.075059 109.367277)
		(width 0.185)
		(layer "F.Cu")
		(net 43)
	)
	(segment
		(start 122.215392 103.132265)
		(end 122.04006 103.132265)
		(width 0.185)
		(layer "F.Cu")
		(net 43)
	)
	(segment
		(start 122.04006 102.142261)
		(end 122.215392 102.142261)
		(width 0.185)
		(layer "F.Cu")
		(net 43)
	)
	(segment
		(start 122.215413 104.452269)
		(end 122.04006 104.452269)
		(width 0.185)
		(layer "F.Cu")
		(net 43)
	)
	(segment
		(start 122.648153 95.71667)
		(end 122.365311 95.71667)
		(width 0.185)
		(layer "F.Cu")
		(net 43)
	)
	(via
		(at 122.648153 95.71667)
		(size 0.55)
		(drill 0.25)
		(layers "F.Cu" "B.Cu")
		(net 43)
	)
	(via
		(at 122.075059 109.367277)
		(size 0.55)
		(drill 0.25)
		(layers "F.Cu" "B.Cu")
		(net 43)
	)
	(arc
		(start 122.710415 103.957267)
		(mid 122.565432 104.307286)
		(end 122.215413 104.452269)
		(width 0.185)
		(layer "F.Cu")
		(net 43)
	)
	(arc
		(start 122.215413 103.462265)
		(mid 122.565432 103.607248)
		(end 122.710415 103.957267)
		(width 0.185)
		(layer "F.Cu")
		(net 43)
	)
	(arc
		(start 122.215392 102.142261)
		(mid 122.565411 102.287244)
		(end 122.710394 102.637263)
		(width 0.185)
		(layer "F.Cu")
		(net 43)
	)
	(arc
		(start 121.87506 104.617269)
		(mid 121.923387 104.733942)
		(end 122.04006 104.782269)
		(width 0.185)
		(layer "F.Cu")
		(net 43)
	)
	(arc
		(start 122.215413 106.102273)
		(mid 122.565432 106.247256)
		(end 122.710415 106.597275)
		(width 0.185)
		(layer "F.Cu")
		(net 43)
	)
	(arc
		(start 121.87506 105.937273)
		(mid 121.923387 106.053946)
		(end 122.04006 106.102273)
		(width 0.185)
		(layer "F.Cu")
		(net 43)
	)
	(arc
		(start 122.710394 102.637263)
		(mid 122.565411 102.987282)
		(end 122.215392 103.132265)
		(width 0.185)
		(layer "F.Cu")
		(net 43)
	)
	(arc
		(start 122.215392 104.782269)
		(mid 122.565411 104.927252)
		(end 122.710394 105.277271)
		(width 0.185)
		(layer "F.Cu")
		(net 43)
	)
	(arc
		(start 121.87506 103.297265)
		(mid 121.923387 103.413938)
		(end 122.04006 103.462265)
		(width 0.185)
		(layer "F.Cu")
		(net 43)
	)
	(arc
		(start 121.87506 101.977261)
		(mid 121.923387 102.093934)
		(end 122.04006 102.142261)
		(width 0.185)
		(layer "F.Cu")
		(net 43)
	)
	(arc
		(start 122.04006 107.092277)
		(mid 121.923387 107.140604)
		(end 121.87506 107.257277)
		(width 0.185)
		(layer "F.Cu")
		(net 43)
	)
	(arc
		(start 122.710415 106.597275)
		(mid 122.565432 106.947294)
		(end 122.215413 107.092277)
		(width 0.185)
		(layer "F.Cu")
		(net 43)
	)
	(arc
		(start 122.04006 105.772273)
		(mid 121.923387 105.8206)
		(end 121.87506 105.937273)
		(width 0.185)
		(layer "F.Cu")
		(net 43)
	)
	(arc
		(start 122.710394 105.277271)
		(mid 122.565411 105.62729)
		(end 122.215392 105.772273)
		(width 0.185)
		(layer "F.Cu")
		(net 43)
	)
	(arc
		(start 122.04006 104.452269)
		(mid 121.923387 104.500596)
		(end 121.87506 104.617269)
		(width 0.185)
		(layer "F.Cu")
		(net 43)
	)
	(arc
		(start 122.04006 103.132265)
		(mid 121.923387 103.180592)
		(end 121.87506 103.297265)
		(width 0.185)
		(layer "F.Cu")
		(net 43)
	)
	(segment
		(start 122.059704 96.022277)
		(end 117.871713 96.022277)
		(width 0.185)
		(layer "B.Cu")
		(net 43)
	)
	(segment
		(start 122.210059 115.662276)
		(end 122.210059 118.812277)
		(width 0.185)
		(layer "B.Cu")
		(net 43)
	)
	(segment
		(start 109.52506 93.76752)
		(end 107.650059 93.76752)
		(width 0.185)
		(layer "B.Cu")
		(net 43)
	)
	(segment
		(start 122.365311 95.71667)
		(end 122.059704 96.022277)
		(width 0.185)
		(layer "B.Cu")
		(net 43)
	)
	(segment
		(start 121.875059 115.327276)
		(end 122.210059 115.662276)
		(width 0.185)
		(layer "B.Cu")
		(net 43)
	)
	(segment
		(start 109.61006 93.68252)
		(end 109.52506 93.76752)
		(width 0.185)
		(layer "B.Cu")
		(net 43)
	)
	(segment
		(start 115.531956 93.68252)
		(end 109.61006 93.68252)
		(width 0.185)
		(layer "B.Cu")
		(net 43)
	)
	(segment
		(start 117.871713 96.022277)
		(end 115.531956 93.68252)
		(width 0.185)
		(layer "B.Cu")
		(net 43)
	)
	(segment
		(start 122.075059 109.367277)
		(end 121.875059 109.567277)
		(width 0.185)
		(layer "B.Cu")
		(net 43)
	)
	(segment
		(start 122.648153 95.71667)
		(end 122.365311 95.71667)
		(width 0.185)
		(layer "B.Cu")
		(net 43)
	)
	(segment
		(start 121.875059 109.567277)
		(end 121.875059 115.327276)
		(width 0.185)
		(layer "B.Cu")
		(net 43)
	)
	(segment
		(start 123.875059 115.332276)
		(end 124.210059 115.667276)
		(width 0.185)
		(layer "F.Cu")
		(net 44)
	)
	(segment
		(start 124.186774 105.740563)
		(end 124.021773 105.740563)
		(width 0.185)
		(layer "F.Cu")
		(net 44)
	)
	(segment
		(start 124.663488 103.787277)
		(end 124.663488 103.863849)
		(width 0.185)
		(layer "F.Cu")
		(net 44)
	)
	(segment
		(start 123.875059 104.487277)
		(end 123.875059 104.563849)
		(width 0.185)
		(layer "F.Cu")
		(net 44)
	)
	(segment
		(start 124.663488 106.587277)
		(end 124.663488 106.663849)
		(width 0.185)
		(layer "F.Cu")
		(net 44)
	)
	(segment
		(start 123.875059 103.087277)
		(end 123.875059 103.163849)
		(width 0.185)
		(layer "F.Cu")
		(net 44)
	)
	(segment
		(start 124.418153 97.17667)
		(end 124.135311 97.17667)
		(width 0.185)
		(layer "F.Cu")
		(net 44)
	)
	(segment
		(start 124.186774 104.340563)
		(end 124.021773 104.340563)
		(width 0.185)
		(layer "F.Cu")
		(net 44)
	)
	(segment
		(start 124.663488 102.387277)
		(end 124.663488 102.463849)
		(width 0.185)
		(layer "F.Cu")
		(net 44)
	)
	(segment
		(start 124.186809 101.540527)
		(end 124.021809 101.540527)
		(width 0.185)
		(layer "F.Cu")
		(net 44)
	)
	(segment
		(start 124.021773 101.910563)
		(end 124.186774 101.910563)
		(width 0.185)
		(layer "F.Cu")
		(net 44)
	)
	(segment
		(start 123.875059 97.436922)
		(end 123.875059 100.363777)
		(width 0.185)
		(layer "F.Cu")
		(net 44)
	)
	(segment
		(start 124.663488 105.187277)
		(end 124.663488 105.263849)
		(width 0.185)
		(layer "F.Cu")
		(net 44)
	)
	(segment
		(start 124.663559 100.987277)
		(end 124.663559 101.063777)
		(width 0.185)
		(layer "F.Cu")
		(net 44)
	)
	(segment
		(start 124.021809 100.510527)
		(end 124.186809 100.510527)
		(width 0.185)
		(layer "F.Cu")
		(net 44)
	)
	(segment
		(start 123.875059 101.687277)
		(end 123.875059 101.763849)
		(width 0.185)
		(layer "F.Cu")
		(net 44)
	)
	(segment
		(start 124.021773 103.310563)
		(end 124.186774 103.310563)
		(width 0.185)
		(layer "F.Cu")
		(net 44)
	)
	(segment
		(start 124.021773 104.710563)
		(end 124.186774 104.710563)
		(width 0.185)
		(layer "F.Cu")
		(net 44)
	)
	(segment
		(start 123.875059 107.287277)
		(end 123.875059 115.332276)
		(width 0.185)
		(layer "F.Cu")
		(net 44)
	)
	(segment
		(start 124.186774 107.140563)
		(end 124.021773 107.140563)
		(width 0.185)
		(layer "F.Cu")
		(net 44)
	)
	(segment
		(start 124.021773 106.110563)
		(end 124.186774 106.110563)
		(width 0.185)
		(layer "F.Cu")
		(net 44)
	)
	(segment
		(start 124.210059 115.667276)
		(end 124.210059 118.817277)
		(width 0.185)
		(layer "F.Cu")
		(net 44)
	)
	(segment
		(start 123.875059 105.887277)
		(end 123.875059 105.963849)
		(width 0.185)
		(layer "F.Cu")
		(net 44)
	)
	(segment
		(start 124.135311 97.17667)
		(end 123.875059 97.436922)
		(width 0.185)
		(layer "F.Cu")
		(net 44)
	)
	(segment
		(start 124.186774 102.940563)
		(end 124.021773 102.940563)
		(width 0.185)
		(layer "F.Cu")
		(net 44)
	)
	(via
		(at 124.418153 97.17667)
		(size 0.55)
		(drill 0.25)
		(layers "F.Cu" "B.Cu")
		(net 44)
	)
	(arc
		(start 124.186774 101.910563)
		(mid 124.523862 102.050189)
		(end 124.663488 102.387277)
		(width 0.185)
		(layer "F.Cu")
		(net 44)
	)
	(arc
		(start 123.875059 104.563849)
		(mid 123.918031 104.667591)
		(end 124.021773 104.710563)
		(width 0.185)
		(layer "F.Cu")
		(net 44)
	)
	(arc
		(start 124.663559 101.063777)
		(mid 124.523922 101.40089)
		(end 124.186809 101.540527)
		(width 0.185)
		(layer "F.Cu")
		(net 44)
	)
	(arc
		(start 124.021773 104.340563)
		(mid 123.918031 104.383535)
		(end 123.875059 104.487277)
		(width 0.185)
		(layer "F.Cu")
		(net 44)
	)
	(arc
		(start 124.186774 104.710563)
		(mid 124.523862 104.850189)
		(end 124.663488 105.187277)
		(width 0.185)
		(layer "F.Cu")
		(net 44)
	)
	(arc
		(start 123.875059 105.963849)
		(mid 123.918031 106.067591)
		(end 124.021773 106.110563)
		(width 0.185)
		(layer "F.Cu")
		(net 44)
	)
	(arc
		(start 124.021773 102.940563)
		(mid 123.918031 102.983535)
		(end 123.875059 103.087277)
		(width 0.185)
		(layer "F.Cu")
		(net 44)
	)
	(arc
		(start 124.186774 103.310563)
		(mid 124.523862 103.450189)
		(end 124.663488 103.787277)
		(width 0.185)
		(layer "F.Cu")
		(net 44)
	)
	(arc
		(start 123.875059 101.763849)
		(mid 123.918031 101.867591)
		(end 124.021773 101.910563)
		(width 0.185)
		(layer "F.Cu")
		(net 44)
	)
	(arc
		(start 123.875059 103.163849)
		(mid 123.918031 103.267591)
		(end 124.021773 103.310563)
		(width 0.185)
		(layer "F.Cu")
		(net 44)
	)
	(arc
		(start 124.186809 100.510527)
		(mid 124.523922 100.650164)
		(end 124.663559 100.987277)
		(width 0.185)
		(layer "F.Cu")
		(net 44)
	)
	(arc
		(start 124.186774 106.110563)
		(mid 124.523862 106.250189)
		(end 124.663488 106.587277)
		(width 0.185)
		(layer "F.Cu")
		(net 44)
	)
	(arc
		(start 124.663488 103.863849)
		(mid 124.523862 104.200937)
		(end 124.186774 104.340563)
		(width 0.185)
		(layer "F.Cu")
		(net 44)
	)
	(arc
		(start 124.021809 101.540527)
		(mid 123.918041 101.583509)
		(end 123.875059 101.687277)
		(width 0.185)
		(layer "F.Cu")
		(net 44)
	)
	(arc
		(start 124.663488 102.463849)
		(mid 124.523862 102.800937)
		(end 124.186774 102.940563)
		(width 0.185)
		(layer "F.Cu")
		(net 44)
	)
	(arc
		(start 124.663488 105.263849)
		(mid 124.523862 105.600937)
		(end 124.186774 105.740563)
		(width 0.185)
		(layer "F.Cu")
		(net 44)
	)
	(arc
		(start 124.021773 107.140563)
		(mid 123.918031 107.183535)
		(end 123.875059 107.287277)
		(width 0.185)
		(layer "F.Cu")
		(net 44)
	)
	(arc
		(start 124.663488 106.663849)
		(mid 124.523862 107.000937)
		(end 124.186774 107.140563)
		(width 0.185)
		(layer "F.Cu")
		(net 44)
	)
	(arc
		(start 124.021773 105.740563)
		(mid 123.918031 105.783535)
		(end 123.875059 105.887277)
		(width 0.185)
		(layer "F.Cu")
		(net 44)
	)
	(arc
		(start 123.875059 100.363777)
		(mid 123.918041 100.467545)
		(end 124.021809 100.510527)
		(width 0.185)
		(layer "F.Cu")
		(net 44)
	)
	(segment
		(start 109.61006 95.18252)
		(end 115.441956 95.18252)
		(width 0.185)
		(layer "B.Cu")
		(net 44)
	)
	(segment
		(start 115.441956 95.18252)
		(end 117.751713 97.492277)
		(width 0.185)
		(layer "B.Cu")
		(net 44)
	)
	(segment
		(start 107.650059 95.26752)
		(end 109.52506 95.26752)
		(width 0.185)
		(layer "B.Cu")
		(net 44)
	)
	(segment
		(start 117.751713 97.492277)
		(end 123.819704 97.492277)
		(width 0.185)
		(layer "B.Cu")
		(net 44)
	)
	(segment
		(start 124.135311 97.17667)
		(end 124.418153 97.17667)
		(width 0.185)
		(layer "B.Cu")
		(net 44)
	)
	(segment
		(start 123.819704 97.492277)
		(end 124.135311 97.17667)
		(width 0.185)
		(layer "B.Cu")
		(net 44)
	)
	(segment
		(start 109.52506 95.26752)
		(end 109.61006 95.18252)
		(width 0.185)
		(layer "B.Cu")
		(net 44)
	)
	(segment
		(start 123.545059 103.087277)
		(end 123.545059 103.163849)
		(width 0.185)
		(layer "F.Cu")
		(net 45)
	)
	(segment
		(start 124.186809 101.210527)
		(end 124.021809 101.210527)
		(width 0.185)
		(layer "F.Cu")
		(net 45)
	)
	(segment
		(start 123.210059 115.667276)
		(end 123.210059 118.817277)
		(width 0.185)
		(layer "F.Cu")
		(net 45)
	)
	(segment
		(start 123.545059 97.30023)
		(end 123.545059 100.363777)
		(width 0.185)
		(layer "F.Cu")
		(net 45)
	)
	(segment
		(start 124.021773 102.240563)
		(end 124.186774 102.240563)
		(width 0.185)
		(layer "F.Cu")
		(net 45)
	)
	(segment
		(start 123.545059 107.287277)
		(end 123.545059 115.332276)
		(width 0.185)
		(layer "F.Cu")
		(net 45)
	)
	(segment
		(start 124.333488 103.787277)
		(end 124.333488 103.863849)
		(width 0.185)
		(layer "F.Cu")
		(net 45)
	)
	(segment
		(start 124.021809 100.840527)
		(end 124.186809 100.840527)
		(width 0.185)
		(layer "F.Cu")
		(net 45)
	)
	(segment
		(start 124.186774 106.810563)
		(end 124.021773 106.810563)
		(width 0.185)
		(layer "F.Cu")
		(net 45)
	)
	(segment
		(start 124.333559 100.987277)
		(end 124.333559 101.063777)
		(width 0.185)
		(layer "F.Cu")
		(net 45)
	)
	(segment
		(start 124.186774 102.610563)
		(end 124.021773 102.610563)
		(width 0.185)
		(layer "F.Cu")
		(net 45)
	)
	(segment
		(start 123.545059 101.687277)
		(end 123.545059 101.763849)
		(width 0.185)
		(layer "F.Cu")
		(net 45)
	)
	(segment
		(start 123.901965 96.660482)
		(end 123.901965 96.943324)
		(width 0.185)
		(layer "F.Cu")
		(net 45)
	)
	(segment
		(start 124.021773 105.040563)
		(end 124.186774 105.040563)
		(width 0.185)
		(layer "F.Cu")
		(net 45)
	)
	(segment
		(start 123.545059 104.487277)
		(end 123.545059 104.563849)
		(width 0.185)
		(layer "F.Cu")
		(net 45)
	)
	(segment
		(start 124.333488 105.187277)
		(end 124.333488 105.263849)
		(width 0.185)
		(layer "F.Cu")
		(net 45)
	)
	(segment
		(start 123.901965 96.943324)
		(end 123.545059 97.30023)
		(width 0.185)
		(layer "F.Cu")
		(net 45)
	)
	(segment
		(start 123.545059 105.887277)
		(end 123.545059 105.963849)
		(width 0.185)
		(layer "F.Cu")
		(net 45)
	)
	(segment
		(start 123.545059 115.332276)
		(end 123.210059 115.667276)
		(width 0.185)
		(layer "F.Cu")
		(net 45)
	)
	(segment
		(start 124.021773 106.440563)
		(end 124.186774 106.440563)
		(width 0.185)
		(layer "F.Cu")
		(net 45)
	)
	(segment
		(start 124.186774 104.010563)
		(end 124.021773 104.010563)
		(width 0.185)
		(layer "F.Cu")
		(net 45)
	)
	(segment
		(start 124.333488 106.587277)
		(end 124.333488 106.663849)
		(width 0.185)
		(layer "F.Cu")
		(net 45)
	)
	(segment
		(start 124.021773 103.640563)
		(end 124.186774 103.640563)
		(width 0.185)
		(layer "F.Cu")
		(net 45)
	)
	(segment
		(start 124.186774 105.410563)
		(end 124.021773 105.410563)
		(width 0.185)
		(layer "F.Cu")
		(net 45)
	)
	(segment
		(start 124.333488 102.387277)
		(end 124.333488 102.463849)
		(width 0.185)
		(layer "F.Cu")
		(net 45)
	)
	(via
		(at 123.901965 96.660482)
		(size 0.55)
		(drill 0.25)
		(layers "F.Cu" "B.Cu")
		(net 45)
	)
	(arc
		(start 123.545059 101.763849)
		(mid 123.684685 102.100937)
		(end 124.021773 102.240563)
		(width 0.185)
		(layer "F.Cu")
		(net 45)
	)
	(arc
		(start 124.186774 102.240563)
		(mid 124.290516 102.283535)
		(end 124.333488 102.387277)
		(width 0.185)
		(layer "F.Cu")
		(net 45)
	)
	(arc
		(start 124.186809 100.840527)
		(mid 124.290577 100.883509)
		(end 124.333559 100.987277)
		(width 0.185)
		(layer "F.Cu")
		(net 45)
	)
	(arc
		(start 124.186774 103.640563)
		(mid 124.290516 103.683535)
		(end 124.333488 103.787277)
		(width 0.185)
		(layer "F.Cu")
		(net 45)
	)
	(arc
		(start 123.545059 104.563849)
		(mid 123.684685 104.900937)
		(end 124.021773 105.040563)
		(width 0.185)
		(layer "F.Cu")
		(net 45)
	)
	(arc
		(start 124.021773 106.810563)
		(mid 123.684685 106.950189)
		(end 123.545059 107.287277)
		(width 0.185)
		(layer "F.Cu")
		(net 45)
	)
	(arc
		(start 124.021773 102.610563)
		(mid 123.684685 102.750189)
		(end 123.545059 103.087277)
		(width 0.185)
		(layer "F.Cu")
		(net 45)
	)
	(arc
		(start 124.186774 106.440563)
		(mid 124.290516 106.483535)
		(end 124.333488 106.587277)
		(width 0.185)
		(layer "F.Cu")
		(net 45)
	)
	(arc
		(start 124.333559 101.063777)
		(mid 124.290577 101.167545)
		(end 124.186809 101.210527)
		(width 0.185)
		(layer "F.Cu")
		(net 45)
	)
	(arc
		(start 124.333488 106.663849)
		(mid 124.290516 106.767591)
		(end 124.186774 106.810563)
		(width 0.185)
		(layer "F.Cu")
		(net 45)
	)
	(arc
		(start 124.021809 101.210527)
		(mid 123.684696 101.350164)
		(end 123.545059 101.687277)
		(width 0.185)
		(layer "F.Cu")
		(net 45)
	)
	(arc
		(start 124.021773 105.410563)
		(mid 123.684685 105.550189)
		(end 123.545059 105.887277)
		(width 0.185)
		(layer "F.Cu")
		(net 45)
	)
	(arc
		(start 124.333488 105.263849)
		(mid 124.290516 105.367591)
		(end 124.186774 105.410563)
		(width 0.185)
		(layer "F.Cu")
		(net 45)
	)
	(arc
		(start 124.333488 103.863849)
		(mid 124.290516 103.967591)
		(end 124.186774 104.010563)
		(width 0.185)
		(layer "F.Cu")
		(net 45)
	)
	(arc
		(start 123.545059 105.963849)
		(mid 123.684685 106.300937)
		(end 124.021773 106.440563)
		(width 0.185)
		(layer "F.Cu")
		(net 45)
	)
	(arc
		(start 124.021773 104.010563)
		(mid 123.684685 104.150189)
		(end 123.545059 104.487277)
		(width 0.185)
		(layer "F.Cu")
		(net 45)
	)
	(arc
		(start 124.186774 105.040563)
		(mid 124.290516 105.083535)
		(end 124.333488 105.187277)
		(width 0.185)
		(layer "F.Cu")
		(net 45)
	)
	(arc
		(start 123.545059 100.363777)
		(mid 123.684696 100.70089)
		(end 124.021809 100.840527)
		(width 0.185)
		(layer "F.Cu")
		(net 45)
	)
	(arc
		(start 123.545059 103.163849)
		(mid 123.684685 103.500937)
		(end 124.021773 103.640563)
		(width 0.185)
		(layer "F.Cu")
		(net 45)
	)
	(arc
		(start 124.333488 102.463849)
		(mid 124.290516 102.567591)
		(end 124.186774 102.610563)
		(width 0.185)
		(layer "F.Cu")
		(net 45)
	)
	(segment
		(start 123.901965 96.943324)
		(end 123.901965 96.660482)
		(width 0.185)
		(layer "B.Cu")
		(net 45)
	)
	(segment
		(start 123.683012 97.162277)
		(end 123.901965 96.943324)
		(width 0.185)
		(layer "B.Cu")
		(net 45)
	)
	(segment
		(start 115.578648 94.85252)
		(end 117.888405 97.162277)
		(width 0.185)
		(layer "B.Cu")
		(net 45)
	)
	(segment
		(start 107.650059 94.76752)
		(end 109.52506 94.76752)
		(width 0.185)
		(layer "B.Cu")
		(net 45)
	)
	(segment
		(start 109.61006 94.85252)
		(end 115.578648 94.85252)
		(width 0.185)
		(layer "B.Cu")
		(net 45)
	)
	(segment
		(start 117.888405 97.162277)
		(end 123.683012 97.162277)
		(width 0.185)
		(layer "B.Cu")
		(net 45)
	)
	(segment
		(start 109.52506 94.76752)
		(end 109.61006 94.85252)
		(width 0.185)
		(layer "B.Cu")
		(net 45)
	)
	(segment
		(start 117.545058 109.137278)
		(end 117.545058 107.197277)
		(width 0.185)
		(layer "F.Cu")
		(net 46)
	)
	(segment
		(start 118.621965 92.293324)
		(end 118.621965 92.010482)
		(width 0.185)
		(layer "F.Cu")
		(net 46)
	)
	(segment
		(start 117.545058 101.917261)
		(end 117.545058 93.370231)
		(width 0.185)
		(layer "F.Cu")
		(net 46)
	)
	(segment
		(start 117.545058 93.370231)
		(end 118.621965 92.293324)
		(width 0.185)
		(layer "F.Cu")
		(net 46)
	)
	(segment
		(start 118.23987 103.732267)
		(end 118.04006 103.732267)
		(width 0.185)
		(layer "F.Cu")
		(net 46)
	)
	(segment
		(start 118.239853 105.052271)
		(end 118.04006 105.052271)
		(width 0.185)
		(layer "F.Cu")
		(net 46)
	)
	(segment
		(start 117.345059 109.337277)
		(end 117.545058 109.137278)
		(width 0.185)
		(layer "F.Cu")
		(net 46)
	)
	(segment
		(start 118.04006 106.702275)
		(end 118.239853 106.702275)
		(width 0.185)
		(layer "F.Cu")
		(net 46)
	)
	(segment
		(start 118.04006 104.062267)
		(end 118.23987 104.062267)
		(width 0.185)
		(layer "F.Cu")
		(net 46)
	)
	(segment
		(start 118.04006 105.382271)
		(end 118.239853 105.382271)
		(width 0.185)
		(layer "F.Cu")
		(net 46)
	)
	(segment
		(start 118.04006 102.742263)
		(end 118.23987 102.742263)
		(width 0.185)
		(layer "F.Cu")
		(net 46)
	)
	(segment
		(start 118.239853 106.372275)
		(end 118.04006 106.372275)
		(width 0.185)
		(layer "F.Cu")
		(net 46)
	)
	(segment
		(start 118.23987 102.412263)
		(end 118.04006 102.412263)
		(width 0.185)
		(layer "F.Cu")
		(net 46)
	)
	(via
		(at 117.345059 109.337277)
		(size 0.55)
		(drill 0.25)
		(layers "F.Cu" "B.Cu")
		(net 46)
	)
	(via
		(at 118.621965 92.010482)
		(size 0.55)
		(drill 0.25)
		(layers "F.Cu" "B.Cu")
		(net 46)
	)
	(arc
		(start 118.40487 102.577263)
		(mid 118.356543 102.46059)
		(end 118.23987 102.412263)
		(width 0.185)
		(layer "F.Cu")
		(net 46)
	)
	(arc
		(start 118.239853 105.382271)
		(mid 118.356526 105.333944)
		(end 118.404853 105.217271)
		(width 0.185)
		(layer "F.Cu")
		(net 46)
	)
	(arc
		(start 118.239853 106.702275)
		(mid 118.356526 106.653948)
		(end 118.404853 106.537275)
		(width 0.185)
		(layer "F.Cu")
		(net 46)
	)
	(arc
		(start 118.04006 103.732267)
		(mid 117.690041 103.587284)
		(end 117.545058 103.237265)
		(width 0.185)
		(layer "F.Cu")
		(net 46)
	)
	(arc
		(start 118.404853 106.537275)
		(mid 118.356526 106.420602)
		(end 118.239853 106.372275)
		(width 0.185)
		(layer "F.Cu")
		(net 46)
	)
	(arc
		(start 117.545058 104.557269)
		(mid 117.690041 104.20725)
		(end 118.04006 104.062267)
		(width 0.185)
		(layer "F.Cu")
		(net 46)
	)
	(arc
		(start 118.23987 102.742263)
		(mid 118.356543 102.693936)
		(end 118.40487 102.577263)
		(width 0.185)
		(layer "F.Cu")
		(net 46)
	)
	(arc
		(start 118.40487 103.897267)
		(mid 118.356543 103.780594)
		(end 118.23987 103.732267)
		(width 0.185)
		(layer "F.Cu")
		(net 46)
	)
	(arc
		(start 118.04006 105.052271)
		(mid 117.690041 104.907288)
		(end 117.545058 104.557269)
		(width 0.185)
		(layer "F.Cu")
		(net 46)
	)
	(arc
		(start 118.04006 102.412263)
		(mid 117.690041 102.26728)
		(end 117.545058 101.917261)
		(width 0.185)
		(layer "F.Cu")
		(net 46)
	)
	(arc
		(start 118.04006 106.372275)
		(mid 117.690041 106.227292)
		(end 117.545058 105.877273)
		(width 0.185)
		(layer "F.Cu")
		(net 46)
	)
	(arc
		(start 118.23987 104.062267)
		(mid 118.356543 104.01394)
		(end 118.40487 103.897267)
		(width 0.185)
		(layer "F.Cu")
		(net 46)
	)
	(arc
		(start 118.404853 105.217271)
		(mid 118.356526 105.100598)
		(end 118.239853 105.052271)
		(width 0.185)
		(layer "F.Cu")
		(net 46)
	)
	(arc
		(start 117.545058 107.197277)
		(mid 117.690041 106.847258)
		(end 118.04006 106.702275)
		(width 0.185)
		(layer "F.Cu")
		(net 46)
	)
	(arc
		(start 117.545058 105.877273)
		(mid 117.690041 105.527254)
		(end 118.04006 105.382271)
		(width 0.185)
		(layer "F.Cu")
		(net 46)
	)
	(arc
		(start 117.545058 103.237265)
		(mid 117.690041 102.887246)
		(end 118.04006 102.742263)
		(width 0.185)
		(layer "F.Cu")
		(net 46)
	)
	(segment
		(start 109.52506 90.26752)
		(end 107.650059 90.26752)
		(width 0.185)
		(layer "B.Cu")
		(net 46)
	)
	(segment
		(start 118.621965 92.293324)
		(end 118.413012 92.502277)
		(width 0.185)
		(layer "B.Cu")
		(net 46)
	)
	(segment
		(start 117.210059 115.662276)
		(end 117.545059 115.327276)
		(width 0.185)
		(layer "B.Cu")
		(net 46)
	)
	(segment
		(start 117.545058 109.537276)
		(end 117.345059 109.337277)
		(width 0.185)
		(layer "B.Cu")
		(net 46)
	)
	(segment
		(start 118.413012 92.502277)
		(end 118.008405 92.502277)
		(width 0.185)
		(layer "B.Cu")
		(net 46)
	)
	(segment
		(start 115.858648 90.35252)
		(end 109.61006 90.35252)
		(width 0.185)
		(layer "B.Cu")
		(net 46)
	)
	(segment
		(start 118.621965 92.010482)
		(end 118.621965 92.293324)
		(width 0.185)
		(layer "B.Cu")
		(net 46)
	)
	(segment
		(start 109.61006 90.35252)
		(end 109.52506 90.26752)
		(width 0.185)
		(layer "B.Cu")
		(net 46)
	)
	(segment
		(start 118.008405 92.502277)
		(end 115.858648 90.35252)
		(width 0.185)
		(layer "B.Cu")
		(net 46)
	)
	(segment
		(start 117.210059 118.812277)
		(end 117.210059 115.662276)
		(width 0.185)
		(layer "B.Cu")
		(net 46)
	)
	(segment
		(start 117.545059 115.327276)
		(end 117.545058 109.537276)
		(width 0.185)
		(layer "B.Cu")
		(net 46)
	)
	(segment
		(start 118.04006 105.712273)
		(end 118.239853 105.712273)
		(width 0.185)
		(layer "F.Cu")
		(net 47)
	)
	(segment
		(start 117.87506 109.137278)
		(end 117.87506 107.197277)
		(width 0.185)
		(layer "F.Cu")
		(net 47)
	)
	(segment
		(start 117.87506 101.917261)
		(end 117.87506 93.506921)
		(width 0.185)
		(layer "F.Cu")
		(net 47)
	)
	(segment
		(start 118.04006 104.392269)
		(end 118.23987 104.392269)
		(width 0.185)
		(layer "F.Cu")
		(net 47)
	)
	(segment
		(start 118.04006 107.032277)
		(end 118.239853 107.032277)
		(width 0.185)
		(layer "F.Cu")
		(net 47)
	)
	(segment
		(start 118.239853 104.722269)
		(end 118.04006 104.722269)
		(width 0.185)
		(layer "F.Cu")
		(net 47)
	)
	(segment
		(start 118.04006 103.072265)
		(end 118.23987 103.072265)
		(width 0.185)
		(layer "F.Cu")
		(net 47)
	)
	(segment
		(start 118.239853 106.042273)
		(end 118.04006 106.042273)
		(width 0.185)
		(layer "F.Cu")
		(net 47)
	)
	(segment
		(start 118.23987 102.082261)
		(end 118.04006 102.082261)
		(width 0.185)
		(layer "F.Cu")
		(net 47)
	)
	(segment
		(start 118.075059 109.337277)
		(end 117.87506 109.137278)
		(width 0.185)
		(layer "F.Cu")
		(net 47)
	)
	(segment
		(start 118.23987 103.402265)
		(end 118.04006 103.402265)
		(width 0.185)
		(layer "F.Cu")
		(net 47)
	)
	(segment
		(start 118.855311 92.52667)
		(end 119.138153 92.52667)
		(width 0.185)
		(layer "F.Cu")
		(net 47)
	)
	(segment
		(start 117.87506 93.506921)
		(end 118.855311 92.52667)
		(width 0.185)
		(layer "F.Cu")
		(net 47)
	)
	(via
		(at 118.075059 109.337277)
		(size 0.55)
		(drill 0.25)
		(layers "F.Cu" "B.Cu")
		(net 47)
	)
	(via
		(at 119.138153 92.52667)
		(size 0.55)
		(drill 0.25)
		(layers "F.Cu" "B.Cu")
		(net 47)
	)
	(arc
		(start 117.87506 107.197277)
		(mid 117.923387 107.080604)
		(end 118.04006 107.032277)
		(width 0.185)
		(layer "F.Cu")
		(net 47)
	)
	(arc
		(start 118.734872 102.577263)
		(mid 118.589889 102.227244)
		(end 118.23987 102.082261)
		(width 0.185)
		(layer "F.Cu")
		(net 47)
	)
	(arc
		(start 118.04006 102.082261)
		(mid 117.923387 102.033934)
		(end 117.87506 101.917261)
		(width 0.185)
		(layer "F.Cu")
		(net 47)
	)
	(arc
		(start 118.04006 104.722269)
		(mid 117.923387 104.673942)
		(end 117.87506 104.557269)
		(width 0.185)
		(layer "F.Cu")
		(net 47)
	)
	(arc
		(start 118.734855 106.537275)
		(mid 118.589872 106.187256)
		(end 118.239853 106.042273)
		(width 0.185)
		(layer "F.Cu")
		(net 47)
	)
	(arc
		(start 118.734855 105.217271)
		(mid 118.589872 104.867252)
		(end 118.239853 104.722269)
		(width 0.185)
		(layer "F.Cu")
		(net 47)
	)
	(arc
		(start 117.87506 103.237265)
		(mid 117.923387 103.120592)
		(end 118.04006 103.072265)
		(width 0.185)
		(layer "F.Cu")
		(net 47)
	)
	(arc
		(start 118.734872 103.897267)
		(mid 118.589889 103.547248)
		(end 118.23987 103.402265)
		(width 0.185)
		(layer "F.Cu")
		(net 47)
	)
	(arc
		(start 118.04006 103.402265)
		(mid 117.923387 103.353938)
		(end 117.87506 103.237265)
		(width 0.185)
		(layer "F.Cu")
		(net 47)
	)
	(arc
		(start 118.23987 104.392269)
		(mid 118.589889 104.247286)
		(end 118.734872 103.897267)
		(width 0.185)
		(layer "F.Cu")
		(net 47)
	)
	(arc
		(start 117.87506 105.877273)
		(mid 117.923387 105.7606)
		(end 118.04006 105.712273)
		(width 0.185)
		(layer "F.Cu")
		(net 47)
	)
	(arc
		(start 118.239853 105.712273)
		(mid 118.589872 105.56729)
		(end 118.734855 105.217271)
		(width 0.185)
		(layer "F.Cu")
		(net 47)
	)
	(arc
		(start 118.23987 103.072265)
		(mid 118.589889 102.927282)
		(end 118.734872 102.577263)
		(width 0.185)
		(layer "F.Cu")
		(net 47)
	)
	(arc
		(start 117.87506 104.557269)
		(mid 117.923387 104.440596)
		(end 118.04006 104.392269)
		(width 0.185)
		(layer "F.Cu")
		(net 47)
	)
	(arc
		(start 118.239853 107.032277)
		(mid 118.589872 106.887294)
		(end 118.734855 106.537275)
		(width 0.185)
		(layer "F.Cu")
		(net 47)
	)
	(arc
		(start 118.04006 106.042273)
		(mid 117.923387 105.993946)
		(end 117.87506 105.877273)
		(width 0.185)
		(layer "F.Cu")
		(net 47)
	)
	(segment
		(start 109.52506 90.76752)
		(end 107.650059 90.76752)
		(width 0.185)
		(layer "B.Cu")
		(net 47)
	)
	(segment
		(start 118.855311 92.52667)
		(end 118.549704 92.832277)
		(width 0.185)
		(layer "B.Cu")
		(net 47)
	)
	(segment
		(start 117.87506 109.537276)
		(end 118.075059 109.337277)
		(width 0.185)
		(layer "B.Cu")
		(net 47)
	)
	(segment
		(start 119.138153 92.52667)
		(end 118.855311 92.52667)
		(width 0.185)
		(layer "B.Cu")
		(net 47)
	)
	(segment
		(start 115.721956 90.68252)
		(end 109.61006 90.68252)
		(width 0.185)
		(layer "B.Cu")
		(net 47)
	)
	(segment
		(start 118.549704 92.832277)
		(end 117.871713 92.832277)
		(width 0.185)
		(layer "B.Cu")
		(net 47)
	)
	(segment
		(start 109.61006 90.68252)
		(end 109.52506 90.76752)
		(width 0.185)
		(layer "B.Cu")
		(net 47)
	)
	(segment
		(start 118.210059 118.812277)
		(end 118.210059 115.662276)
		(width 0.185)
		(layer "B.Cu")
		(net 47)
	)
	(segment
		(start 117.871713 92.832277)
		(end 115.721956 90.68252)
		(width 0.185)
		(layer "B.Cu")
		(net 47)
	)
	(segment
		(start 117.875059 115.327276)
		(end 117.87506 109.537276)
		(width 0.185)
		(layer "B.Cu")
		(net 47)
	)
	(segment
		(start 118.210059 115.662276)
		(end 117.875059 115.327276)
		(width 0.185)
		(layer "B.Cu")
		(net 47)
	)
	(segment
		(start 120.220951 104.372277)
		(end 120.040059 104.372277)
		(width 0.185)
		(layer "F.Cu")
		(net 48)
	)
	(segment
		(start 120.040059 102.062277)
		(end 120.220949 102.062277)
		(width 0.185)
		(layer "F.Cu")
		(net 48)
	)
	(segment
		(start 120.535311 94.07667)
		(end 119.875059 94.736922)
		(width 0.185)
		(layer "F.Cu")
		(net 48)
	)
	(segment
		(start 120.220949 103.052277)
		(end 120.040059 103.052277)
		(width 0.185)
		(layer "F.Cu")
		(net 48)
	)
	(segment
		(start 120.220953 107.012277)
		(end 120.040059 107.012277)
		(width 0.185)
		(layer "F.Cu")
		(net 48)
	)
	(segment
		(start 120.818153 94.07667)
		(end 120.535311 94.07667)
		(width 0.185)
		(layer "F.Cu")
		(net 48)
	)
	(segment
		(start 119.875059 107.177277)
		(end 119.875059 115.332276)
		(width 0.185)
		(layer "F.Cu")
		(net 48)
	)
	(segment
		(start 120.22096 101.732277)
		(end 120.040059 101.732277)
		(width 0.185)
		(layer "F.Cu")
		(net 48)
	)
	(segment
		(start 119.875059 115.332276)
		(end 120.210059 115.667276)
		(width 0.185)
		(layer "F.Cu")
		(net 48)
	)
	(segment
		(start 119.875059 94.736922)
		(end 119.875059 100.577277)
		(width 0.185)
		(layer "F.Cu")
		(net 48)
	)
	(segment
		(start 120.210059 115.667276)
		(end 120.210059 118.817277)
		(width 0.185)
		(layer "F.Cu")
		(net 48)
	)
	(segment
		(start 120.040059 103.382277)
		(end 120.220951 103.382277)
		(width 0.185)
		(layer "F.Cu")
		(net 48)
	)
	(segment
		(start 120.040059 104.702277)
		(end 120.220953 104.702277)
		(width 0.185)
		(layer "F.Cu")
		(net 48)
	)
	(segment
		(start 120.220953 105.692277)
		(end 120.040059 105.692277)
		(width 0.185)
		(layer "F.Cu")
		(net 48)
	)
	(segment
		(start 120.040059 100.742277)
		(end 120.22096 100.742277)
		(width 0.185)
		(layer "F.Cu")
		(net 48)
	)
	(segment
		(start 120.040059 106.022277)
		(end 120.220953 106.022277)
		(width 0.185)
		(layer "F.Cu")
		(net 48)
	)
	(via
		(at 120.818153 94.07667)
		(size 0.55)
		(drill 0.25)
		(layers "F.Cu" "B.Cu")
		(net 48)
	)
	(arc
		(start 120.715953 105.197277)
		(mid 120.570971 105.547295)
		(end 120.220953 105.692277)
		(width 0.185)
		(layer "F.Cu")
		(net 48)
	)
	(arc
		(start 120.040059 107.012277)
		(mid 119.923386 107.060604)
		(end 119.875059 107.177277)
		(width 0.185)
		(layer "F.Cu")
		(net 48)
	)
	(arc
		(start 119.875059 104.537277)
		(mid 119.923386 104.65395)
		(end 120.040059 104.702277)
		(width 0.185)
		(layer "F.Cu")
		(net 48)
	)
	(arc
		(start 119.875059 100.577277)
		(mid 119.923386 100.69395)
		(end 120.040059 100.742277)
		(width 0.185)
		(layer "F.Cu")
		(net 48)
	)
	(arc
		(start 120.71596 101.237277)
		(mid 120.570978 101.587295)
		(end 120.22096 101.732277)
		(width 0.185)
		(layer "F.Cu")
		(net 48)
	)
	(arc
		(start 120.715953 106.517277)
		(mid 120.570971 106.867295)
		(end 120.220953 107.012277)
		(width 0.185)
		(layer "F.Cu")
		(net 48)
	)
	(arc
		(start 120.040059 104.372277)
		(mid 119.923386 104.420604)
		(end 119.875059 104.537277)
		(width 0.185)
		(layer "F.Cu")
		(net 48)
	)
	(arc
		(start 120.220953 104.702277)
		(mid 120.570971 104.847259)
		(end 120.715953 105.197277)
		(width 0.185)
		(layer "F.Cu")
		(net 48)
	)
	(arc
		(start 120.220953 106.022277)
		(mid 120.570971 106.167259)
		(end 120.715953 106.517277)
		(width 0.185)
		(layer "F.Cu")
		(net 48)
	)
	(arc
		(start 120.715951 103.877277)
		(mid 120.570969 104.227295)
		(end 120.220951 104.372277)
		(width 0.185)
		(layer "F.Cu")
		(net 48)
	)
	(arc
		(start 120.220951 103.382277)
		(mid 120.570969 103.527259)
		(end 120.715951 103.877277)
		(width 0.185)
		(layer "F.Cu")
		(net 48)
	)
	(arc
		(start 120.040059 101.732277)
		(mid 119.923386 101.780604)
		(end 119.875059 101.897277)
		(width 0.185)
		(layer "F.Cu")
		(net 48)
	)
	(arc
		(start 120.040059 105.692277)
		(mid 119.923386 105.740604)
		(end 119.875059 105.857277)
		(width 0.185)
		(layer "F.Cu")
		(net 48)
	)
	(arc
		(start 120.040059 103.052277)
		(mid 119.923386 103.100604)
		(end 119.875059 103.217277)
		(width 0.185)
		(layer "F.Cu")
		(net 48)
	)
	(arc
		(start 119.875059 101.897277)
		(mid 119.923386 102.01395)
		(end 120.040059 102.062277)
		(width 0.185)
		(layer "F.Cu")
		(net 48)
	)
	(arc
		(start 120.715949 102.557277)
		(mid 120.570967 102.907295)
		(end 120.220949 103.052277)
		(width 0.185)
		(layer "F.Cu")
		(net 48)
	)
	(arc
		(start 119.875059 103.217277)
		(mid 119.923386 103.33395)
		(end 120.040059 103.382277)
		(width 0.185)
		(layer "F.Cu")
		(net 48)
	)
	(arc
		(start 120.220949 102.062277)
		(mid 120.570967 102.207259)
		(end 120.715949 102.557277)
		(width 0.185)
		(layer "F.Cu")
		(net 48)
	)
	(arc
		(start 119.875059 105.857277)
		(mid 119.923386 105.97395)
		(end 120.040059 106.022277)
		(width 0.185)
		(layer "F.Cu")
		(net 48)
	)
	(arc
		(start 120.22096 100.742277)
		(mid 120.570978 100.887259)
		(end 120.71596 101.237277)
		(width 0.185)
		(layer "F.Cu")
		(net 48)
	)
	(segment
		(start 120.209704 94.402277)
		(end 117.857464 94.402277)
		(width 0.185)
		(layer "B.Cu")
		(net 48)
	)
	(segment
		(start 109.52506 92.26752)
		(end 107.650059 92.26752)
		(width 0.185)
		(layer "B.Cu")
		(net 48)
	)
	(segment
		(start 115.637707 92.18252)
		(end 109.61006 92.18252)
		(width 0.185)
		(layer "B.Cu")
		(net 48)
	)
	(segment
		(start 120.535311 94.07667)
		(end 120.209704 94.402277)
		(width 0.185)
		(layer "B.Cu")
		(net 48)
	)
	(segment
		(start 109.61006 92.18252)
		(end 109.52506 92.26752)
		(width 0.185)
		(layer "B.Cu")
		(net 48)
	)
	(segment
		(start 117.857464 94.402277)
		(end 115.637707 92.18252)
		(width 0.185)
		(layer "B.Cu")
		(net 48)
	)
	(segment
		(start 120.818153 94.07667)
		(end 120.535311 94.07667)
		(width 0.185)
		(layer "B.Cu")
		(net 48)
	)
	(segment
		(start 120.301965 93.843324)
		(end 119.545059 94.60023)
		(width 0.185)
		(layer "F.Cu")
		(net 49)
	)
	(segment
		(start 119.210059 115.667276)
		(end 119.210059 118.817277)
		(width 0.185)
		(layer "F.Cu")
		(net 49)
	)
	(segment
		(start 120.22096 101.402277)
		(end 120.040059 101.402277)
		(width 0.185)
		(layer "F.Cu")
		(net 49)
	)
	(segment
		(start 120.220951 104.042277)
		(end 120.040059 104.042277)
		(width 0.185)
		(layer "F.Cu")
		(net 49)
	)
	(segment
		(start 120.040059 102.392277)
		(end 120.220949 102.392277)
		(width 0.185)
		(layer "F.Cu")
		(net 49)
	)
	(segment
		(start 119.545059 94.60023)
		(end 119.545059 100.577277)
		(width 0.185)
		(layer "F.Cu")
		(net 49)
	)
	(segment
		(start 120.040059 106.352277)
		(end 120.220953 106.352277)
		(width 0.185)
		(layer "F.Cu")
		(net 49)
	)
	(segment
		(start 120.220953 105.362277)
		(end 120.040059 105.362277)
		(width 0.185)
		(layer "F.Cu")
		(net 49)
	)
	(segment
		(start 120.220949 102.722277)
		(end 120.040059 102.722277)
		(width 0.185)
		(layer "F.Cu")
		(net 49)
	)
	(segment
		(start 120.220953 106.682277)
		(end 120.040059 106.682277)
		(width 0.185)
		(layer "F.Cu")
		(net 49)
	)
	(segment
		(start 119.545059 107.177277)
		(end 119.545059 115.332276)
		(width 0.185)
		(layer "F.Cu")
		(net 49)
	)
	(segment
		(start 120.301965 93.560482)
		(end 120.301965 93.843324)
		(width 0.185)
		(layer "F.Cu")
		(net 49)
	)
	(segment
		(start 119.545059 115.332276)
		(end 119.210059 115.667276)
		(width 0.185)
		(layer "F.Cu")
		(net 49)
	)
	(segment
		(start 120.040059 101.072277)
		(end 120.22096 101.072277)
		(width 0.185)
		(layer "F.Cu")
		(net 49)
	)
	(segment
		(start 120.040059 105.032277)
		(end 120.220953 105.032277)
		(width 0.185)
		(layer "F.Cu")
		(net 49)
	)
	(segment
		(start 120.040059 103.712277)
		(end 120.220951 103.712277)
		(width 0.185)
		(layer "F.Cu")
		(net 49)
	)
	(via
		(at 120.301965 93.560482)
		(size 0.55)
		(drill 0.25)
		(layers "F.Cu" "B.Cu")
		(net 49)
	)
	(arc
		(start 119.545059 100.577277)
		(mid 119.690041 100.927295)
		(end 120.040059 101.072277)
		(width 0.185)
		(layer "F.Cu")
		(net 49)
	)
	(arc
		(start 120.040059 106.682277)
		(mid 119.690041 106.827259)
		(end 119.545059 107.177277)
		(width 0.185)
		(layer "F.Cu")
		(net 49)
	)
	(arc
		(start 120.385949 102.557277)
		(mid 120.337622 102.67395)
		(end 120.220949 102.722277)
		(width 0.185)
		(layer "F.Cu")
		(net 49)
	)
	(arc
		(start 120.040059 105.362277)
		(mid 119.690041 105.507259)
		(end 119.545059 105.857277)
		(width 0.185)
		(layer "F.Cu")
		(net 49)
	)
	(arc
		(start 120.040059 104.042277)
		(mid 119.690041 104.187259)
		(end 119.545059 104.537277)
		(width 0.185)
		(layer "F.Cu")
		(net 49)
	)
	(arc
		(start 120.22096 101.072277)
		(mid 120.337633 101.120604)
		(end 120.38596 101.237277)
		(width 0.185)
		(layer "F.Cu")
		(net 49)
	)
	(arc
		(start 120.385951 103.877277)
		(mid 120.337624 103.99395)
		(end 120.220951 104.042277)
		(width 0.185)
		(layer "F.Cu")
		(net 49)
	)
	(arc
		(start 119.545059 105.857277)
		(mid 119.690041 106.207295)
		(end 120.040059 106.352277)
		(width 0.185)
		(layer "F.Cu")
		(net 49)
	)
	(arc
		(start 120.040059 102.722277)
		(mid 119.690041 102.867259)
		(end 119.545059 103.217277)
		(width 0.185)
		(layer "F.Cu")
		(net 49)
	)
	(arc
		(start 120.38596 101.237277)
		(mid 120.337633 101.35395)
		(end 120.22096 101.402277)
		(width 0.185)
		(layer "F.Cu")
		(net 49)
	)
	(arc
		(start 120.220949 102.392277)
		(mid 120.337622 102.440604)
		(end 120.385949 102.557277)
		(width 0.185)
		(layer "F.Cu")
		(net 49)
	)
	(arc
		(start 120.040059 101.402277)
		(mid 119.690041 101.547259)
		(end 119.545059 101.897277)
		(width 0.185)
		(layer "F.Cu")
		(net 49)
	)
	(arc
		(start 120.385953 105.197277)
		(mid 120.337626 105.31395)
		(end 120.220953 105.362277)
		(width 0.185)
		(layer "F.Cu")
		(net 49)
	)
	(arc
		(start 120.220951 103.712277)
		(mid 120.337624 103.760604)
		(end 120.385951 103.877277)
		(width 0.185)
		(layer "F.Cu")
		(net 49)
	)
	(arc
		(start 119.545059 104.537277)
		(mid 119.690041 104.887295)
		(end 120.040059 105.032277)
		(width 0.185)
		(layer "F.Cu")
		(net 49)
	)
	(arc
		(start 120.220953 105.032277)
		(mid 120.337626 105.080604)
		(end 120.385953 105.197277)
		(width 0.185)
		(layer "F.Cu")
		(net 49)
	)
	(arc
		(start 120.220953 106.352277)
		(mid 120.337626 106.400604)
		(end 120.385953 106.517277)
		(width 0.185)
		(layer "F.Cu")
		(net 49)
	)
	(arc
		(start 120.385953 106.517277)
		(mid 120.337626 106.63395)
		(end 120.220953 106.682277)
		(width 0.185)
		(layer "F.Cu")
		(net 49)
	)
	(arc
		(start 119.545059 103.217277)
		(mid 119.690041 103.567295)
		(end 120.040059 103.712277)
		(width 0.185)
		(layer "F.Cu")
		(net 49)
	)
	(arc
		(start 119.545059 101.897277)
		(mid 119.690041 102.247295)
		(end 120.040059 102.392277)
		(width 0.185)
		(layer "F.Cu")
		(net 49)
	)
	(segment
		(start 120.301965 93.560482)
		(end 120.301965 93.843324)
		(width 0.185)
		(layer "B.Cu")
		(net 49)
	)
	(segment
		(start 115.774399 91.85252)
		(end 109.61006 91.85252)
		(width 0.185)
		(layer "B.Cu")
		(net 49)
	)
	(segment
		(start 120.301965 93.843324)
		(end 120.073012 94.072277)
		(width 0.185)
		(layer "B.Cu")
		(net 49)
	)
	(segment
		(start 109.52506 91.76752)
		(end 107.650059 91.76752)
		(width 0.185)
		(layer "B.Cu")
		(net 49)
	)
	(segment
		(start 109.61006 91.85252)
		(end 109.52506 91.76752)
		(width 0.185)
		(layer "B.Cu")
		(net 49)
	)
	(segment
		(start 117.994156 94.072277)
		(end 115.774399 91.85252)
		(width 0.185)
		(layer "B.Cu")
		(net 49)
	)
	(segment
		(start 120.073012 94.072277)
		(end 117.994156 94.072277)
		(width 0.185)
		(layer "B.Cu")
		(net 49)
	)
	(segment
		(start 111.180059 101.552034)
		(end 107.91861 101.552034)
		(width 0.25)
		(layer "F.Cu")
		(net 59)
	)
	(segment
		(start 113.890059 104.307277)
		(end 113.890059 104.262034)
		(width 0.25)
		(layer "F.Cu")
		(net 59)
	)
	(segment
		(start 113.890059 104.262034)
		(end 111.180059 101.552034)
		(width 0.25)
		(layer "F.Cu")
		(net 59)
	)
	(via
		(at 113.890059 104.307277)
		(size 0.55)
		(drill 0.25)
		(layers "F.Cu" "B.Cu")
		(net 59)
	)
	(segment
		(start 135.680059 108.597277)
		(end 135.680059 108.602277)
		(width 0.25)
		(layer "B.Cu")
		(net 59)
	)
	(segment
		(start 117.030059 107.447277)
		(end 134.530059 107.447277)
		(width 0.25)
		(layer "B.Cu")
		(net 59)
	)
	(segment
		(start 134.530059 107.447277)
		(end 135.680059 108.597277)
		(width 0.25)
		(layer "B.Cu")
		(net 59)
	)
	(segment
		(start 113.890059 104.307277)
		(end 117.030059 107.447277)
		(width 0.25)
		(layer "B.Cu")
		(net 59)
	)
	(segment
		(start 115.210059 115.517277)
		(end 115.260059 115.467277)
		(width 0.25)
		(layer "F.Cu")
		(net 60)
	)
	(segment
		(start 125.210059 115.581378)
		(end 125.210059 118.812263)
		(width 0.25)
		(layer "F.Cu")
		(net 60)
	)
	(segment
		(start 118.210059 118.812263)
		(end 118.210059 115.678782)
		(width 0.25)
		(layer "F.Cu")
		(net 60)
	)
	(segment
		(start 131.210059 115.678782)
		(end 131.759894 115.128947)
		(width 0.25)
		(layer "F.Cu")
		(net 60)
	)
	(segment
		(start 122.210059 115.678782)
		(end 122.759894 115.128947)
		(width 0.25)
		(layer "F.Cu")
		(net 60)
	)
	(segment
		(start 118.210059 115.678782)
		(end 118.759894 115.128947)
		(width 0.25)
		(layer "F.Cu")
		(net 60)
	)
	(segment
		(start 115.210059 118.812263)
		(end 115.210059 115.517277)
		(width 0.25)
		(layer "F.Cu")
		(net 60)
	)
	(segment
		(start 122.210059 118.812263)
		(end 122.210059 115.678782)
		(width 0.25)
		(layer "F.Cu")
		(net 60)
	)
	(segment
		(start 126.210059 115.678782)
		(end 126.759894 115.128947)
		(width 0.25)
		(layer "F.Cu")
		(net 60)
	)
	(segment
		(start 129.260059 114.967277)
		(end 129.260059 118.762263)
		(width 0.25)
		(layer "F.Cu")
		(net 60)
	)
	(segment
		(start 120.757639 115.128958)
		(end 121.210059 115.581378)
		(width 0.25)
		(layer "F.Cu")
		(net 60)
	)
	(segment
		(start 121.210059 115.581378)
		(end 121.210059 118.812263)
		(width 0.25)
		(layer "F.Cu")
		(net 60)
	)
	(segment
		(start 124.757639 115.128958)
		(end 125.210059 115.581378)
		(width 0.25)
		(layer "F.Cu")
		(net 60)
	)
	(segment
		(start 126.210059 118.812263)
		(end 126.210059 115.678782)
		(width 0.25)
		(layer "F.Cu")
		(net 60)
	)
	(segment
		(start 131.210059 118.812263)
		(end 131.210059 115.678782)
		(width 0.25)
		(layer "F.Cu")
		(net 60)
	)
	(segment
		(start 129.260059 118.762263)
		(end 129.210059 118.812263)
		(width 0.25)
		(layer "F.Cu")
		(net 60)
	)
	(segment
		(start 142.210059 118.812263)
		(end 142.210059 115.637277)
		(width 0.25)
		(layer "F.Cu")
		(net 60)
	)
	(segment
		(start 145.210059 118.812263)
		(end 145.210059 115.757277)
		(width 0.25)
		(layer "F.Cu")
		(net 60)
	)
	(segment
		(start 134.210059 118.812263)
		(end 134.210059 115.457982)
		(width 0.25)
		(layer "F.Cu")
		(net 60)
	)
	(segment
		(start 134.210059 115.457982)
		(end 134.700059 114.967982)
		(width 0.25)
		(layer "F.Cu")
		(net 60)
	)
	(segment
		(start 145.210059 115.757277)
		(end 144.970059 115.517277)
		(width 0.25)
		(layer "F.Cu")
		(net 60)
	)
	(segment
		(start 142.210059 115.637277)
		(end 142.450059 115.397277)
		(width 0.25)
		(layer "F.Cu")
		(net 60)
	)
	(via
		(at 120.757639 115.128958)
		(size 0.6)
		(drill 0.3)
		(layers "F.Cu" "B.Cu")
		(net 60)
	)
	(via
		(at 116.260059 115.467277)
		(size 0.6)
		(drill 0.3)
		(layers "F.Cu" "B.Cu")
		(net 60)
	)
	(via
		(at 115.260059 115.467277)
		(size 0.6)
		(drill 0.3)
		(layers "F.Cu" "B.Cu")
		(net 60)
	)
	(via
		(at 124.757639 115.128958)
		(size 0.6)
		(drill 0.3)
		(layers "F.Cu" "B.Cu")
		(net 60)
	)
	(via
		(at 131.759894 115.128947)
		(size 0.6)
		(drill 0.3)
		(layers "F.Cu" "B.Cu")
		(net 60)
	)
	(via
		(at 129.260059 114.967277)
		(size 0.6)
		(drill 0.3)
		(layers "F.Cu" "B.Cu")
		(net 60)
	)
	(via
		(at 118.759894 115.128947)
		(size 0.6)
		(drill 0.3)
		(layers "F.Cu" "B.Cu")
		(net 60)
	)
	(via
		(at 126.759894 115.128947)
		(size 0.6)
		(drill 0.3)
		(layers "F.Cu" "B.Cu")
		(net 60)
	)
	(via
		(at 122.759894 115.128947)
		(size 0.6)
		(drill 0.3)
		(layers "F.Cu" "B.Cu")
		(net 60)
	)
	(via
		(at 186.190009 98.759778)
		(size 5.5)
		(drill 3.5)
		(layers "F.Cu" "B.Cu")
		(net 60)
	)
	(via
		(at 110.200059 98.76752)
		(size 0.55)
		(drill 0.25)
		(layers "F.Cu" "B.Cu")
		(net 60)
	)
	(via
		(at 136.242295 104.866964)
		(size 0.6)
		(drill 0.3)
		(layers "F.Cu" "B.Cu")
		(net 60)
	)
	(via
		(at 144.970059 115.517277)
		(size 0.6)
		(drill 0.3)
		(layers "F.Cu" "B.Cu")
		(net 60)
	)
	(via
		(at 110.190059 105.287277)
		(size 0.6)
		(drill 0.3)
		(layers "F.Cu" "B.Cu")
		(net 60)
	)
	(via
		(at 144.000059 112.497277)
		(size 0.55)
		(drill 0.25)
		(layers "F.Cu" "B.Cu")
		(net 60)
	)
	(via
		(at 123.350059 96.047277)
		(size 0.6)
		(drill 0.3)
		(layers "F.Cu" "B.Cu")
		(net 60)
	)
	(via
		(at 120.952559 110.04788)
		(size 0.6)
		(drill 0.3)
		(layers "F.Cu" "B.Cu")
		(free yes)
		(net 60)
	)
	(via
		(at 110.160059 103.26752)
		(size 0.55)
		(drill 0.25)
		(layers "F.Cu" "B.Cu")
		(net 60)
	)
	(via
		(at 121.600059 94.447277)
		(size 0.6)
		(drill 0.3)
		(layers "F.Cu" "B.Cu")
		(net 60)
	)
	(via
		(at 134.467559 111.561872)
		(size 0.6)
		(drill 0.3)
		(layers "F.Cu" "B.Cu")
		(free yes)
		(net 60)
	)
	(via
		(at 122.494417 110.019019)
		(size 0.6)
		(drill 0.3)
		(layers "F.Cu" "B.Cu")
		(free yes)
		(net 60)
	)
	(via
		(at 112.200853 101.766726)
		(size 0.6)
		(drill 0.3)
		(layers "F.Cu" "B.Cu")
		(net 60)
	)
	(via
		(at 129.952558 110.059833)
		(size 0.6)
		(drill 0.3)
		(layers "F.Cu" "B.Cu")
		(free yes)
		(net 60)
	)
	(via
		(at 110.200059 100.267277)
		(size 0.55)
		(drill 0.25)
		(layers "F.Cu" "B.Cu")
		(net 60)
	)
	(via
		(at 116.952558 110.035127)
		(size 0.6)
		(drill 0.3)
		(layers "F.Cu" "B.Cu")
		(free yes)
		(net 60)
	)
	(via
		(at 127.450059 99.047277)
		(size 0.6)
		(drill 0.3)
		(layers "F.Cu" "B.Cu")
		(net 60)
	)
	(via
		(at 125.250059 97.497277)
		(size 0.6)
		(drill 0.3)
		(layers "F.Cu" "B.Cu")
		(net 60)
	)
	(via
		(at 112.150059 89.802034)
		(size 0.55)
		(drill 0.25)
		(layers "F.Cu" "B.Cu")
		(net 60)
	)
	(via
		(at 110.200059 94.267277)
		(size 0.55)
		(drill 0.25)
		(layers "F.Cu" "B.Cu")
		(net 60)
	)
	(via
		(at 124.952558 110.12136)
		(size 0.6)
		(drill 0.3)
		(layers "F.Cu" "B.Cu")
		(free yes)
		(net 60)
	)
	(via
		(at 134.700059 114.967982)
		(size 0.6)
		(drill 0.3)
		(layers "F.Cu" "B.Cu")
		(net 60)
	)
	(via
		(at 131.46756 110.063118)
		(size 0.6)
		(drill 0.3)
		(layers "F.Cu" "B.Cu")
		(free yes)
		(net 60)
	)
	(via
		(at 137.062459 113.112277)
		(size 0.55)
		(drill 0.25)
		(layers "F.Cu" "B.Cu")
		(net 60)
	)
	(via
		(at 119.950059 92.747277)
		(size 0.6)
		(drill 0.3)
		(layers "F.Cu" "B.Cu")
		(net 60)
	)
	(via
		(at 110.200059 97.267277)
		(size 0.55)
		(drill 0.25)
		(layers "F.Cu" "B.Cu")
		(net 60)
	)
	(via
		(at 140.590059 111.497277)
		(size 0.55)
		(drill 0.25)
		(layers "F.Cu" "B.Cu")
		(net 60)
	)
	(via
		(at 110.200059 95.767277)
		(size 0.55)
		(drill 0.25)
		(layers "F.Cu" "B.Cu")
		(net 60)
	)
	(via
		(at 126.479645 110.108291)
		(size 0.6)
		(drill 0.3)
		(layers "F.Cu" "B.Cu")
		(free yes)
		(net 60)
	)
	(via
		(at 118.46756 110.010582)
		(size 0.6)
		(drill 0.3)
		(layers "F.Cu" "B.Cu")
		(free yes)
		(net 60)
	)
	(via
		(at 145.230059 113.047277)
		(size 0.55)
		(drill 0.25)
		(layers "F.Cu" "B.Cu")
		(net 60)
	)
	(via
		(at 143.637559 111.217277)
		(size 0.55)
		(drill 0.25)
		(layers "F.Cu" "B.Cu")
		(net 60)
	)
	(via
		(at 118.53078 91.296277)
		(size 0.6)
		(drill 0.3)
		(layers "F.Cu" "B.Cu")
		(net 60)
	)
	(via
		(at 115.255059 88.567277)
		(size 0.55)
		(drill 0.25)
		(layers "F.Cu" "B.Cu")
		(net 60)
	)
	(via
		(at 142.450059 115.397277)
		(size 0.6)
		(drill 0.3)
		(layers "F.Cu" "B.Cu")
		(net 60)
	)
	(via
		(at 114.525059 92.772277)
		(size 0.6)
		(drill 0.3)
		(layers "F.Cu" "B.Cu")
		(net 60)
	)
	(via
		(at 134.350059 103.497277)
		(size 0.6)
		(drill 0.3)
		(layers "F.Cu" "B.Cu")
		(net 60)
	)
	(via
		(at 133.927433 109.367398)
		(size 0.6)
		(drill 0.3)
		(layers "F.Cu" "B.Cu")
		(free yes)
		(net 60)
	)
	(via
		(at 132.450059 102.047277)
		(size 0.6)
		(drill 0.3)
		(layers "F.Cu" "B.Cu")
		(net 60)
	)
	(via
		(at 111.700059 105.317277)
		(size 0.6)
		(drill 0.3)
		(layers "F.Cu" "B.Cu")
		(net 60)
	)
	(via
		(at 129.900059 100.547277)
		(size 0.6)
		(drill 0.3)
		(layers "F.Cu" "B.Cu")
		(net 60)
	)
	(via
		(at 110.930059 105.317277)
		(size 0.6)
		(drill 0.3)
		(layers "F.Cu" "B.Cu")
		(net 60)
	)
	(via
		(at 110.200059 91.22002)
		(size 0.6)
		(drill 0.3)
		(layers "F.Cu" "B.Cu")
		(net 60)
	)
	(segment
		(start 120.210059 115.676538)
		(end 120.757639 115.128958)
		(width 0.25)
		(layer "B.Cu")
		(net 60)
	)
	(segment
		(start 127.210059 115.579112)
		(end 127.210059 118.807309)
		(width 0.25)
		(layer "B.Cu")
		(net 60)
	)
	(segment
		(start 123.210059 115.579112)
		(end 123.210059 118.807309)
		(width 0.25)
		(layer "B.Cu")
		(net 60)
	)
	(segment
		(start 129.210059 115.017277)
		(end 129.260059 114.967277)
		(width 0.25)
		(layer "B.Cu")
		(net 60)
	)
	(segment
		(start 116.210059 115.517277)
		(end 116.260059 115.467277)
		(width 0.25)
		(layer "B.Cu")
		(net 60)
	)
	(segment
		(start 124.210059 115.676538)
		(end 124.757639 115.128958)
		(width 0.25)
		(layer "B.Cu")
		(net 60)
	)
	(segment
		(start 132.210059 115.579112)
		(end 132.210059 118.807309)
		(width 0.25)
		(layer "B.Cu")
		(net 60)
	)
	(segment
		(start 116.210059 118.807309)
		(end 116.210059 115.517277)
		(width 0.25)
		(layer "B.Cu")
		(net 60)
	)
	(segment
		(start 119.210059 115.579112)
		(end 118.759894 115.128947)
		(width 0.25)
		(layer "B.Cu")
		(net 60)
	)
	(segment
		(start 119.210059 118.807309)
		(end 119.210059 115.579112)
		(width 0.25)
		(layer "B.Cu")
		(net 60)
	)
	(segment
		(start 129.210059 118.807309)
		(end 129.210059 115.017277)
		(width 0.25)
		(layer "B.Cu")
		(net 60)
	)
	(segment
		(start 122.759894 115.128947)
		(end 123.210059 115.579112)
		(width 0.25)
		(layer "B.Cu")
		(net 60)
	)
	(segment
		(start 126.759894 115.128947)
		(end 127.210059 115.579112)
		(width 0.25)
		(layer "B.Cu")
		(net 60)
	)
	(segment
		(start 124.210059 118.807309)
		(end 124.210059 115.676538)
		(width 0.25)
		(layer "B.Cu")
		(net 60)
	)
	(segment
		(start 131.759894 115.128947)
		(end 132.210059 115.579112)
		(width 0.25)
		(layer "B.Cu")
		(net 60)
	)
	(segment
		(start 120.210059 118.807309)
		(end 120.210059 115.676538)
		(width 0.25)
		(layer "B.Cu")
		(net 60)
	)
	(segment
		(start 137.045059 112.367277)
		(end 137.045059 113.592277)
		(width 0.25)
		(layer "B.Cu")
		(net 60)
	)
	(segment
		(start 183.320059 98.767277)
		(end 183.328212 98.759124)
		(width 1.5)
		(layer "B.Cu")
		(net 60)
	)
	(segment
		(start 110.200059 95.767277)
		(end 107.650302 95.767277)
		(width 0.25)
		(layer "B.Cu")
		(net 60)
	)
	(segment
		(start 144.000059 112.497277)
		(end 143.200059 112.497277)
		(width 0.25)
		(layer "B.Cu")
		(net 60)
	)
	(segment
		(start 113.820059 89.337277)
		(end 114.590059 88.567277)
		(width 0.25)
		(layer "B.Cu")
		(net 60)
	)
	(segment
		(start 142.780059 111.197277)
		(end 143.617559 111.197277)
		(width 0.25)
		(layer "B.Cu")
		(net 60)
	)
	(segment
		(start 174.244205 98.759778)
		(end 183.31256 98.759778)
		(width 1.5)
		(layer "B.Cu")
		(net 60)
	)
	(segment
		(start 110.160059 103.26752)
		(end 107.650059 103.26752)
		(width 0.25)
		(layer "B.Cu")
		(net 60)
	)
	(segment
		(start 183.328212 98.759124)
		(end 185.229922 98.759124)
		(width 1.5)
		(layer "B.Cu")
		(net 60)
	)
	(segment
		(start 107.650302 100.267277)
		(end 107.650059 100.26752)
		(width 0.25)
		(layer "B.Cu")
		(net 60)
	)
	(segment
		(start 135.210059 115.477982)
		(end 134.700059 114.967982)
		(width 0.25)
		(layer "B.Cu")
		(net 60)
	)
	(segment
		(start 140.590059 112.397277)
		(end 140.590059 111.497277)
		(width 0.25)
		(layer "B.Cu")
		(net 60)
	)
	(segment
		(start 135.210059 118.807309)
		(end 135.210059 115.477982)
		(width 0.25)
		(layer "B.Cu")
		(net 60)
	)
	(segment
		(start 112.200059 101.76752)
		(end 107.650059 101.76752)
		(width 0.25)
		(layer "B.Cu")
		(net 60)
	)
	(segment
		(start 110.200059 91.22002)
		(end 110.152559 91.26752)
		(width 0.25)
		(layer "B.Cu")
		(net 60)
	)
	(segment
		(start 142.450059 114.767277)
		(end 142.450059 115.397277)
		(width 0.25)
		(layer "B.Cu")
		(net 60)
	)
	(segment
		(start 143.200059 114.017277)
		(end 142.450059 114.767277)
		(width 0.25)
		(layer "B.Cu")
		(net 60)
	)
	(segment
		(start 115.255059 88.567277)
		(end 114.590059 88.567277)
		(width 0.25)
		(layer "B.Cu")
		(net 60)
	)
	(segment
		(start 137.045059 113.129677)
		(end 137.062459 113.112277)
		(width 0.25)
		(layer "B.Cu")
		(net 60)
	)
	(segment
		(start 107.650302 94.267277)
		(end 107.650059 94.26752)
		(width 0.25)
		(layer "B.Cu")
		(net 60)
	)
	(segment
		(start 145.230059 113.047277)
		(end 145.230059 112.377277)
		(width 0.25)
		(layer "B.Cu")
		(net 60)
	)
	(segment
		(start 144.810059 115.357277)
		(end 144.970059 115.517277)
		(width 0.25)
		(layer "B.Cu")
		(net 60)
	)
	(segment
		(start 145.210059 118.807309)
		(end 145.210059 115.757277)
		(width 0.25)
		(layer "B.Cu")
		(net 60)
	)
	(segment
		(start 107.650059 89.26752)
		(end 107.719816 89.337277)
		(width 0.25)
		(layer "B.Cu")
		(net 60)
	)
	(segment
		(start 110.200059 100.267277)
		(end 107.650302 100.267277)
		(width 0.25)
		(layer "B.Cu")
		(net 60)
	)
	(segment
		(start 110.930059 105.317277)
		(end 110.930059 104.537277)
		(width 0.2)
		(layer "B.Cu")
		(net 60)
	)
	(segment
		(start 112.150059 89.802034)
		(end 107.91861 89.802034)
		(width 0.25)
		(layer "B.Cu")
		(net 60)
	)
	(segment
		(start 112.200853 101.766726)
		(end 112.200059 101.76752)
		(width 0.25)
		(layer "B.Cu")
		(net 60)
	)
	(segment
		(start 114.525059 92.772277)
		(end 114.520302 92.76752)
		(width 0.2)
		(layer "B.Cu")
		(net 60)
	)
	(segment
		(start 137.045059 113.592277)
		(end 137.045059 113.129677)
		(width 0.25)
		(layer "B.Cu")
		(net 60)
	)
	(segment
		(start 145.210059 115.757277)
		(end 144.970059 115.517277)
		(width 0.25)
		(layer "B.Cu")
		(net 60)
	)
	(segment
		(start 110.930059 104.537277)
		(end 111.040059 104.427277)
		(width 0.2)
		(layer "B.Cu")
		(net 60)
	)
	(segment
		(start 110.200059 94.267277)
		(end 107.650302 94.267277)
		(width 0.25)
		(layer "B.Cu")
		(net 60)
	)
	(segment
		(start 143.617559 111.197277)
		(end 143.637559 111.217277)
		(width 0.25)
		(layer "B.Cu")
		(net 60)
	)
	(segment
		(start 183.31256 98.759778)
		(end 183.320059 98.767277)
		(width 1.5)
		(layer "B.Cu")
		(net 60)
	)
	(segment
		(start 110.152559 91.26752)
		(end 107.650059 91.26752)
		(width 0.25)
		(layer "B.Cu")
		(net 60)
	)
	(segment
		(start 173.050059 96.137277)
		(end 173.050059 97.565632)
		(width 1.5)
		(layer "B.Cu")
		(net 60)
	)
	(segment
		(start 107.650302 95.767277)
		(end 107.650059 95.76752)
		(width 0.25)
		(layer "B.Cu")
		(net 60)
	)
	(segment
		(start 107.719816 89.337277)
		(end 113.820059 89.337277)
		(width 0.25)
		(layer "B.Cu")
		(net 60)
	)
	(segment
		(start 145.230059 112.377277)
		(end 145.240059 112.367277)
		(width 0.25)
		(layer "B.Cu")
		(net 60)
	)
	(segment
		(start 110.200059 97.267277)
		(end 107.650302 97.267277)
		(width 0.25)
		(layer "B.Cu")
		(net 60)
	)
	(segment
		(start 173.050059 97.565632)
		(end 174.244205 98.759778)
		(width 1.5)
		(layer "B.Cu")
		(net 60)
	)
	(segment
		(start 137.045059 113.592277)
		(end 136.620059 114.017277)
		(width 0.25)
		(layer "B.Cu")
		(net 60)
	)
	(segment
		(start 114.520302 92.76752)
		(end 107.650059 92.76752)
		(width 0.2)
		(layer "B.Cu")
		(net 60)
	)
	(segment
		(start 110.200059 98.76752)
		(end 107.650059 98.76752)
		(width 0.25)
		(layer "B.Cu")
		(net 60)
	)
	(segment
		(start 107.650302 97.267277)
		(end 107.650059 97.26752)
		(width 0.25)
		(layer "B.Cu")
		(net 60)
	)
	(segment
		(start 144.810059 114.017277)
		(end 144.810059 115.357277)
		(width 0.25)
		(layer "B.Cu")
		(net 60)
	)
	(segment
		(start 170.081704 92.597277)
		(end 181.790059 92.597277)
		(width 1.5)
		(layer "F.Cu")
		(net 61)
	)
	(segment
		(start 167.970059 94.708922)
		(end 170.081704 92.597277)
		(width 1.5)
		(layer "F.Cu")
		(net 61)
	)
	(segment
		(start 167.970059 96.137277)
		(end 167.970059 94.708922)
		(width 1.5)
		(layer "F.Cu")
		(net 61)
	)
	(segment
		(start 139.210059 115.937277)
		(end 138.480059 115.207277)
		(width 0.25)
		(layer "F.Cu")
		(net 62)
	)
	(segment
		(start 139.210059 118.812263)
		(end 139.210059 115.937277)
		(width 0.25)
		(layer "F.Cu")
		(net 62)
	)
	(via
		(at 138.480059 115.207277)
		(size 0.55)
		(drill 0.25)
		(layers "F.Cu" "B.Cu")
		(net 62)
	)
	(segment
		(start 138.020059 114.017277)
		(end 138.020059 112.372277)
		(width 0.25)
		(layer "B.Cu")
		(net 62)
	)
	(segment
		(start 138.010059 112.367277)
		(end 138.010059 107.437277)
		(width 0.25)
		(layer "B.Cu")
		(net 62)
	)
	(segment
		(start 138.020059 114.747277)
		(end 138.020059 114.017277)
		(width 0.25)
		(layer "B.Cu")
		(net 62)
	)
	(segment
		(start 138.010059 107.437277)
		(end 138.000059 107.427277)
		(width 0.25)
		(layer "B.Cu")
		(net 62)
	)
	(segment
		(start 138.480059 115.207277)
		(end 138.020059 114.747277)
		(width 0.25)
		(layer "B.Cu")
		(net 62)
	)
	(segment
		(start 138.020059 112.372277)
		(end 138.015059 112.367277)
		(width 0.25)
		(layer "B.Cu")
		(net 62)
	)
	(segment
		(start 110.374816 102.552034)
		(end 107.91861 102.552034)
		(width 0.25)
		(layer "F.Cu")
		(net 63)
	)
	(segment
		(start 111.400059 103.597277)
		(end 111.400059 103.577277)
		(width 0.25)
		(layer "F.Cu")
		(net 63)
	)
	(segment
		(start 111.400059 103.577277)
		(end 110.374816 102.552034)
		(width 0.25)
		(layer "F.Cu")
		(net 63)
	)
	(via
		(at 111.400059 103.597277)
		(size 0.55)
		(drill 0.25)
		(layers "F.Cu" "B.Cu")
		(net 63)
	)
	(segment
		(start 111.400059 103.597277)
		(end 114.050059 103.597277)
		(width 0.25)
		(layer "B.Cu")
		(net 63)
	)
	(segment
		(start 137.195059 108.552277)
		(end 137.200059 108.552277)
		(width 0.25)
		(layer "B.Cu")
		(net 63)
	)
	(segment
		(start 135.490059 106.847277)
		(end 137.195059 108.552277)
		(width 0.25)
		(layer "B.Cu")
		(net 63)
	)
	(segment
		(start 117.300059 106.847277)
		(end 135.490059 106.847277)
		(width 0.25)
		(layer "B.Cu")
		(net 63)
	)
	(segment
		(start 114.050059 103.597277)
		(end 117.300059 106.847277)
		(width 0.25)
		(layer "B.Cu")
		(net 63)
	)
	(zone
		(net 61)
		(net_name "+5V")
		(layer "F.Cu")
		(hatch edge 0.508)
		(connect_pads yes
			(clearance 0.508)
		)
		(min_thickness 0.254)
		(filled_areas_thickness no)
		(fill yes
			(thermal_gap 0.508)
			(thermal_bridge_width 0.508)
		)
		(polygon
			(pts
				(xy 186.210059 97.917277) (xy 177.590059 97.937277) (xy 177.575059 87.677277) (xy 186.210059 87.677277)
			)
		)
	)
	(zone
		(net 30)
		(net_name "+12V")
		(layer "F.Cu")
		(hatch edge 0.508)
		(connect_pads yes
			(clearance 0.508)
		)
		(min_thickness 0.254)
		(filled_areas_thickness no)
		(fill yes
			(thermal_gap 0.508)
			(thermal_bridge_width 0.508)
		)
		(polygon
			(pts
				(xy 151.630059 109.491006) (xy 151.617365 111.555483) (xy 144.342753 111.539072) (xy 144.335067 105.567441)
				(xy 177.590059 105.567277) (xy 177.600059 99.617277) (xy 186.191696 99.619777) (xy 186.200059 109.497277)
			)
		)
	)
	(zone
		(net 31)
		(net_name "/+3V3")
		(layer "F.Cu")
		(hatch edge 0.508)
		(priority 1)
		(connect_pads
			(clearance 0.3)
		)
		(min_thickness 0.2)
		(filled_areas_thickness no)
		(fill yes
			(thermal_gap 0.508)
			(thermal_bridge_width 0.508)
		)
		(polygon
			(pts
				(xy 106.400059 106.047277) (xy 106.400059 107.847277) (xy 116.300059 107.847277) (xy 116.500059 107.647277)
				(xy 116.500059 92.747277) (xy 118.100059 91.147277) (xy 119.900059 91.147277) (xy 121.200059 92.447277)
				(xy 131.500059 92.447277) (xy 136.500059 97.447277) (xy 136.500059 103.747277) (xy 141.000059 103.747277)
				(xy 141.000059 87.647277) (xy 112.800059 87.647277) (xy 111.100059 89.347277) (xy 110.200059 89.347277)
				(xy 110.200059 93.747277) (xy 113.475059 93.747277) (xy 113.775059 94.022277) (xy 113.775059 103.037277)
				(xy 114.330059 103.587277) (xy 114.330059 105.547277) (xy 113.825059 106.047277)
			)
		)
	)
	(zone
		(net 60)
		(net_name "GND")
		(layer "B.Cu")
		(hatch edge 0.508)
		(priority 2)
		(connect_pads
			(clearance 0.2)
		)
		(min_thickness 0.2)
		(filled_areas_thickness no)
		(fill yes
			(thermal_gap 0.508)
			(thermal_bridge_width 0.508)
		)
		(polygon
			(pts
				(xy 106.400059 106.547277) (xy 106.400059 108.047277) (xy 111.100059 108.047277) (xy 112.100059 107.047277)
				(xy 112.100059 105.147277) (xy 111.900059 104.947277) (xy 110.000059 104.947277) (xy 109.800059 105.147277)
				(xy 109.800059 106.247277) (xy 109.500059 106.547277)
			)
		)
	)
	(zone
		(net 60)
		(net_name "GND")
		(layers "In1.Cu" "In2.Cu")
		(hatch edge 0.508)
		(connect_pads
			(clearance 0.3)
		)
		(min_thickness 0.2)
		(filled_areas_thickness no)
		(fill yes
			(thermal_gap 0.508)
			(thermal_bridge_width 0.508)
		)
		(polygon
			(pts
				(xy 106.200059 108.427277) (xy 111.800059 108.427277) (xy 111.800059 109.527277) (xy 111.810059 121.387277)
				(xy 151.610117 121.467704) (xy 151.630001 109.517277) (xy 186.200059 109.527277) (xy 186.200059 87.577277)
				(xy 135.950059 87.577277) (xy 111.600059 87.577277) (xy 111.600059 88.677277) (xy 106.200059 88.677277)
				(xy 106.200059 104.077277) (xy 109.700059 104.077277) (xy 109.700059 105.277277) (xy 106.200059 105.277277)
			)
		)
	)
)
